FILE_TYPE = MACRO_DRAWING;
SET COLOR_WIRE YELLOW;
SET COLOR_PROP MONO;
SET COLOR_DOT WHITE;
SET COLOR_ARC YELLOW;
SET COLOR_BODY GREEN;
SET COLOR_NOTE MONO;
SET PROP_DISPLAY VALUE;
SET PAGE_NUMBER P133;
FORCEADD GND..1
(-2825 3600);
FORCEPROP 3 LASTPIN (-2825 3650) SIG_NAME GND\g
J 0
(-2815 3660);
DISPLAY 0.659574 (-2815 3660);
PAINT MONO (-2815 3660);
DISPLAY INVISIBLE (-2815 3660);
FORCEPROP 1 LAST SIZE 1B
J 0
(-2750 3550);
DISPLAY 1.468085 (-2750 3550);
PAINT GREEN (-2750 3550);
DISPLAY INVISIBLE (-2750 3550);
FORCEPROP 2 LAST CDS_LIB mstr_symbols
J 0
(-2825 3600);
PAINT MONO (-2825 3600);
DISPLAY INVISIBLE (-2825 3600);
FORCEPROP 2 LAST BOM_COST SB
J 0
(-2875 3675);
PAINT MONO (-2875 3675);
DISPLAY INVISIBLE (-2875 3675);
FORCEPROP 1 LAST VOLTAGE 0
J 0
(-2825 3600);
PAINT SKYBLUE (-2825 3600);
DISPLAY INVISIBLE (-2825 3600);
FORCEPROP 1 LAST PATH I110
J 0
(-2750 3600);
DISPLAY 1.170213 (-2750 3600);
PAINT GREEN (-2750 3600);
DISPLAY INVISIBLE (-2750 3600);
FORCEPROP 1 LAST BODY_TYPE PLUMBING
J 0
(-2870 3557);
DISPLAY 0.340426 (-2870 3557);
PAINT GREEN (-2870 3557);
DISPLAY INVISIBLE (-2870 3557);
FORCEPROP 1 LAST HDL_POWER GND
J 0
(-2825 3750);
DISPLAY 1.468085 (-2825 3750);
PAINT GREEN (-2825 3750);
DISPLAY INVISIBLE (-2825 3750);
FORCEADD OFFPAGE..2
(-1600 4075);
FORCEPROP 2 LAST $XR3 247 
J 0
(-1051 4075);
DISPLAY 0.638298 (-1051 4075);
PAINT MONO (-1051 4075);
FORCEPROP 2 LAST $XR2 144 
J 0
(-1171 4075);
DISPLAY 0.638298 (-1171 4075);
PAINT MONO (-1171 4075);
FORCEPROP 2 LAST $XR1 118 
J 0
(-1291 4075);
DISPLAY 0.638298 (-1291 4075);
PAINT MONO (-1291 4075);
FORCEPROP 2 LAST $XR0 191 
J 0
(-1411 4075);
DISPLAY 0.638298 (-1411 4075);
PAINT MONO (-1411 4075);
FORCEPROP 2 LAST CDS_LIB mstr_standard
J 0
(-1600 4075);
PAINT MONO (-1600 4075);
DISPLAY INVISIBLE (-1600 4075);
FORCEPROP 2 LAST PATH I112
J 0
(-1425 4150);
PAINT MONO (-1425 4150);
DISPLAY INVISIBLE (-1425 4150);
FORCEPROP 2 LAST BOM_COST SB
J 0
(-1150 4125);
PAINT MONO (-1150 4125);
DISPLAY INVISIBLE (-1150 4125);
FORCEPROP 1 LAST OFFPAGE TRUE
J 0
(-1275 3950);
PAINT GREEN (-1275 3950);
DISPLAY INVISIBLE (-1275 3950);
FORCEPROP 1 LAST COMMENT_BODY TRUE
J 0
(-1645 3980);
DISPLAY 1.170213 (-1645 3980);
PAINT GREEN (-1645 3980);
DISPLAY INVISIBLE (-1645 3980);
FORCEADD OFFPAGE..2
(-1600 3850);
FORCEPROP 2 LAST $XR2 144 
J 0
(-1171 3850);
DISPLAY 0.638298 (-1171 3850);
PAINT MONO (-1171 3850);
FORCEPROP 2 LAST $XR1 118 
J 0
(-1291 3850);
DISPLAY 0.638298 (-1291 3850);
PAINT MONO (-1291 3850);
FORCEPROP 2 LAST $XR0 191 
J 0
(-1411 3850);
DISPLAY 0.638298 (-1411 3850);
PAINT MONO (-1411 3850);
FORCEPROP 2 LAST CDS_LIB mstr_standard
J 0
(-1600 3850);
PAINT MONO (-1600 3850);
DISPLAY INVISIBLE (-1600 3850);
FORCEPROP 2 LAST PATH I117
J 0
(-1425 3925);
PAINT MONO (-1425 3925);
DISPLAY INVISIBLE (-1425 3925);
FORCEPROP 2 LAST BOM_COST SB
J 0
(-1050 3900);
PAINT MONO (-1050 3900);
DISPLAY INVISIBLE (-1050 3900);
FORCEPROP 1 LAST OFFPAGE TRUE
J 0
(-1275 3725);
PAINT GREEN (-1275 3725);
DISPLAY INVISIBLE (-1275 3725);
FORCEPROP 1 LAST COMMENT_BODY TRUE
J 0
(-1645 3755);
DISPLAY 1.170213 (-1645 3755);
PAINT GREEN (-1645 3755);
DISPLAY INVISIBLE (-1645 3755);
FORCEADD RES..1
(-2500 3850);
FORCEPROP 1 LAST WATTAGE 1/16W
J 2
(-2570 3760);
DISPLAY 0.617021 (-2570 3760);
PAINT SKYBLUE (-2570 3760);
FORCEPROP 1 LAST LOCATION R3N3
J 0
(-2750 3875);
DISPLAY 0.617021 (-2750 3875);
PAINT AQUA (-2750 3875);
FORCEPROP 1 LASTPIN (-2400 3850) $PN 2
J 0
(-2438 3862);
DISPLAY 0.617021 (-2438 3862);
PAINT MONO (-2438 3862);
FORCEPROP 1 LAST PACK_TYPE 0402
J 0
(-2390 3810);
DISPLAY 0.617021 (-2390 3810);
PAINT SKYBLUE (-2390 3810);
FORCEPROP 1 LAST TOLERANCE 1%
J 0
(-2470 3800);
DISPLAY 0.617021 (-2470 3800);
PAINT SKYBLUE (-2470 3800);
FORCEPROP 1 LAST MATERIAL CHIP
J 0
(-2560 3760);
DISPLAY 0.617021 (-2560 3760);
PAINT SKYBLUE (-2560 3760);
FORCEPROP 1 LAST VALUE 2.0K
J 2
(-2525 3800);
DISPLAY 0.617021 (-2525 3800);
PAINT SKYBLUE (-2525 3800);
FORCEPROP 1 LASTPIN (-2600 3850) $PN 1
J 0
(-2588 3862);
DISPLAY 0.617021 (-2588 3862);
PAINT MONO (-2588 3862);
FORCEPROP 1 LAST PART_NUMBER G21796-001
J 0
(-2425 3900);
DISPLAY 0.617021 (-2425 3900);
PAINT BLUE (-2425 3900);
FORCEPROP 2 LAST CDS_LOCATION R3N3
J 0
(-2750 3875);
DISPLAY 0.617021 (-2750 3875);
PAINT AQUA (-2750 3875);
DISPLAY INVISIBLE (-2750 3875);
FORCEPROP 2 LAST BOM_COST SB
J 0
(-2550 3700);
PAINT MONO (-2550 3700);
DISPLAY INVISIBLE (-2550 3700);
FORCEPROP 2 LAST ROOM SB
J 0
(-2500 3850);
PAINT MONO (-2500 3850);
DISPLAY INVISIBLE (-2500 3850);
FORCEPROP 2 LAST CDS_LIB mstr_discrete
J 0
(-2500 3850);
PAINT MONO (-2500 3850);
DISPLAY INVISIBLE (-2500 3850);
FORCEPROP 2 LAST $SEC 1
J 0
(-2550 4050);
DISPLAY 0.936170 (-2550 4050);
PAINT MONO (-2550 4050);
DISPLAY INVISIBLE (-2550 4050);
FORCEPROP 1 LAST PATH I120
J 0
(-2550 4000);
DISPLAY 1.319149 (-2550 4000);
PAINT GREEN (-2550 4000);
DISPLAY INVISIBLE (-2550 4000);
FORCEPROP 2 LAST CDS_SEC 1
J 0
(-2550 4050);
DISPLAY 1.404255 (-2550 4050);
PAINT ORANGE (-2550 4050);
DISPLAY INVISIBLE (-2550 4050);
FORCEADD RES..1
(-2500 4075);
FORCEPROP 1 LAST VALUE 10.0K
J 2
(-2525 4025);
DISPLAY 0.617021 (-2525 4025);
PAINT SKYBLUE (-2525 4025);
FORCEPROP 1 LAST TOLERANCE 1%
J 0
(-2470 4025);
DISPLAY 0.617021 (-2470 4025);
PAINT SKYBLUE (-2470 4025);
FORCEPROP 1 LAST PACK_TYPE 0402
J 0
(-2390 4035);
DISPLAY 0.617021 (-2390 4035);
PAINT SKYBLUE (-2390 4035);
FORCEPROP 1 LASTPIN (-2400 4075) $PN 2
J 0
(-2438 4087);
DISPLAY 0.617021 (-2438 4087);
PAINT MONO (-2438 4087);
FORCEPROP 1 LASTPIN (-2600 4075) $PN 1
J 0
(-2588 4087);
DISPLAY 0.617021 (-2588 4087);
PAINT MONO (-2588 4087);
FORCEPROP 1 LAST LOCATION R2N12
J 0
(-2750 4100);
DISPLAY 0.617021 (-2750 4100);
PAINT AQUA (-2750 4100);
FORCEPROP 1 LAST PART_NUMBER G21796-016
J 0
(-2425 4125);
DISPLAY 0.617021 (-2425 4125);
PAINT BLUE (-2425 4125);
FORCEPROP 1 LAST WATTAGE 1/16W
J 2
(-2620 3985);
DISPLAY 0.617021 (-2620 3985);
PAINT SKYBLUE (-2620 3985);
FORCEPROP 1 LAST MATERIAL EMPTY
J 0
(-2560 3985);
DISPLAY 0.617021 (-2560 3985);
PAINT RED (-2560 3985);
FORCEPROP 2 LAST BOM_COST SB
J 0
(-2550 3925);
PAINT MONO (-2550 3925);
DISPLAY INVISIBLE (-2550 3925);
FORCEPROP 2 LAST ROOM SB
J 0
(-2500 4075);
PAINT MONO (-2500 4075);
DISPLAY INVISIBLE (-2500 4075);
FORCEPROP 2 LAST CDS_LIB mstr_discrete
J 0
(-2500 4075);
PAINT MONO (-2500 4075);
DISPLAY INVISIBLE (-2500 4075);
FORCEPROP 2 LAST CDS_LOCATION R2N12
J 0
(-2750 4100);
DISPLAY 0.617021 (-2750 4100);
PAINT AQUA (-2750 4100);
DISPLAY INVISIBLE (-2750 4100);
FORCEPROP 2 LAST CDS_SEC 1
J 0
(-2550 4275);
DISPLAY 1.404255 (-2550 4275);
PAINT ORANGE (-2550 4275);
DISPLAY INVISIBLE (-2550 4275);
FORCEPROP 2 LAST $SEC 1
J 0
(-2550 4275);
DISPLAY 0.936170 (-2550 4275);
PAINT MONO (-2550 4275);
DISPLAY INVISIBLE (-2550 4275);
FORCEPROP 1 LAST PATH I122
J 0
(-2550 4225);
DISPLAY 1.319149 (-2550 4225);
PAINT GREEN (-2550 4225);
DISPLAY INVISIBLE (-2550 4225);
FORCEADD RES..1
(-4700 4500);
FORCEPROP 1 LASTPIN (-4800 4500) $PN 1
J 0
(-4788 4512);
DISPLAY 0.617021 (-4788 4512);
PAINT ORANGE (-4788 4512);
FORCEPROP 1 LAST VALUE 10.0K
J 2
(-4700 4450);
DISPLAY 0.617021 (-4700 4450);
PAINT SKYBLUE (-4700 4450);
FORCEPROP 1 LAST TOLERANCE 1%
J 0
(-4675 4450);
DISPLAY 0.617021 (-4675 4450);
PAINT SKYBLUE (-4675 4450);
FORCEPROP 1 LAST PACK_TYPE 0402
J 0
(-4300 4450);
DISPLAY 0.617021 (-4300 4450);
PAINT SKYBLUE (-4300 4450);
FORCEPROP 1 LAST PART_NUMBER G21796-016
J 0
(-4175 4450);
DISPLAY 0.617021 (-4175 4450);
PAINT BLUE (-4175 4450);
FORCEPROP 1 LAST WATTAGE 1/16W
J 2
(-4450 4450);
DISPLAY 0.617021 (-4450 4450);
PAINT SKYBLUE (-4450 4450);
FORCEPROP 1 LASTPIN (-4600 4500) $PN 2
J 0
(-4638 4512);
DISPLAY 0.617021 (-4638 4512);
PAINT ORANGE (-4638 4512);
FORCEPROP 1 LAST LOCATION R7D8
J 0
(-4750 4550);
DISPLAY 0.617021 (-4750 4550);
PAINT AQUA (-4750 4550);
FORCEPROP 1 LAST MATERIAL CHIP
J 0
(-4425 4450);
DISPLAY 0.617021 (-4425 4450);
PAINT SKYBLUE (-4425 4450);
FORCEPROP 2 LAST CDS_LOCATION R7D8
J 0
(-4750 4550);
DISPLAY 0.617021 (-4750 4550);
PAINT AQUA (-4750 4550);
DISPLAY INVISIBLE (-4750 4550);
FORCEPROP 2 LAST CDS_LIB mstr_discrete
J 0
(-4700 4500);
PAINT ORANGE (-4700 4500);
DISPLAY INVISIBLE (-4700 4500);
FORCEPROP 0 LAST ROOM SB
J 0
(-4750 4650);
DISPLAY 1.021277 (-4750 4650);
PAINT ORANGE (-4750 4650);
DISPLAY INVISIBLE (-4750 4650);
FORCEPROP 2 LAST SEC_TYPE 0402
J 0
(-4750 4700);
DISPLAY 1.021277 (-4750 4700);
PAINT ORANGE (-4750 4700);
DISPLAY INVISIBLE (-4750 4700);
FORCEPROP 2 LAST SEC 1
J 0
(-4750 4700);
DISPLAY 0.680851 (-4750 4700);
PAINT MONO (-4750 4700);
DISPLAY INVISIBLE (-4750 4700);
FORCEPROP 1 LAST PATH I200
J 0
(-4750 4650);
DISPLAY 0.978723 (-4750 4650);
PAINT WHITE (-4750 4650);
DISPLAY INVISIBLE (-4750 4650);
FORCEADD RES..1
(-4700 4325);
FORCEPROP 1 LASTPIN (-4600 4325) $PN 2
J 0
(-4638 4337);
DISPLAY 0.617021 (-4638 4337);
PAINT ORANGE (-4638 4337);
FORCEPROP 1 LASTPIN (-4800 4325) $PN 1
J 0
(-4788 4337);
DISPLAY 0.617021 (-4788 4337);
PAINT ORANGE (-4788 4337);
FORCEPROP 1 LAST LOCATION R7D10
J 0
(-4750 4375);
DISPLAY 0.617021 (-4750 4375);
PAINT AQUA (-4750 4375);
FORCEPROP 1 LAST VALUE 10.0K
J 2
(-4700 4275);
DISPLAY 0.617021 (-4700 4275);
PAINT SKYBLUE (-4700 4275);
FORCEPROP 1 LAST TOLERANCE 1%
J 0
(-4675 4275);
DISPLAY 0.617021 (-4675 4275);
PAINT SKYBLUE (-4675 4275);
FORCEPROP 1 LAST PART_NUMBER G21796-016
J 0
(-4175 4275);
DISPLAY 0.617021 (-4175 4275);
PAINT BLUE (-4175 4275);
FORCEPROP 1 LAST PACK_TYPE 0402
J 0
(-4300 4275);
DISPLAY 0.617021 (-4300 4275);
PAINT SKYBLUE (-4300 4275);
FORCEPROP 1 LAST MATERIAL CHIP
J 0
(-4425 4275);
DISPLAY 0.617021 (-4425 4275);
PAINT SKYBLUE (-4425 4275);
FORCEPROP 1 LAST WATTAGE 1/16W
J 2
(-4450 4275);
DISPLAY 0.617021 (-4450 4275);
PAINT SKYBLUE (-4450 4275);
FORCEPROP 2 LAST CDS_LIB mstr_discrete
J 0
(-4700 4325);
PAINT ORANGE (-4700 4325);
DISPLAY INVISIBLE (-4700 4325);
FORCEPROP 1 LAST PATH I202
J 0
(-4750 4475);
DISPLAY 0.978723 (-4750 4475);
PAINT WHITE (-4750 4475);
DISPLAY INVISIBLE (-4750 4475);
FORCEPROP 2 LAST CDS_LOCATION R7D10
J 0
(-4750 4375);
DISPLAY 0.617021 (-4750 4375);
PAINT AQUA (-4750 4375);
DISPLAY INVISIBLE (-4750 4375);
FORCEPROP 2 LAST SEC 1
J 0
(-4750 4525);
DISPLAY 0.680851 (-4750 4525);
PAINT MONO (-4750 4525);
DISPLAY INVISIBLE (-4750 4525);
FORCEPROP 2 LAST SEC_TYPE 0402
J 0
(-4750 4525);
DISPLAY 1.021277 (-4750 4525);
PAINT ORANGE (-4750 4525);
DISPLAY INVISIBLE (-4750 4525);
FORCEPROP 0 LAST ROOM SB
J 0
(-4750 4475);
DISPLAY 1.021277 (-4750 4475);
PAINT ORANGE (-4750 4475);
DISPLAY INVISIBLE (-4750 4475);
FORCEADD OFFPAGE..2
(-3850 5100);
FORCEPROP 2 LASTPIN (-3900 5100) SIG_NAME PU_FM_RCIN_N
J 0
(-4435 5110);
DISPLAY 0.617021 (-4435 5110);
PAINT ORANGE (-4435 5110);
FORCEPROP 2 LAST $XR0 119 
J 0
(-3661 5100);
DISPLAY 0.638298 (-3661 5100);
PAINT MONO (-3661 5100);
FORCEPROP 2 LAST CDS_LIB mstr_standard
J 0
(-3850 5100);
PAINT ORANGE (-3850 5100);
DISPLAY INVISIBLE (-3850 5100);
FORCEPROP 2 LAST PATH I204
J 0
(-3675 5175);
DISPLAY 1.021277 (-3675 5175);
PAINT ORANGE (-3675 5175);
DISPLAY INVISIBLE (-3675 5175);
FORCEPROP 1 LAST OFFPAGE TRUE
J 0
(-3525 4975);
DISPLAY 0.872340 (-3525 4975);
PAINT GREEN (-3525 4975);
DISPLAY INVISIBLE (-3525 4975);
FORCEPROP 1 LAST COMMENT_BODY TRUE
J 0
(-3895 5005);
DISPLAY 0.872340 (-3895 5005);
PAINT GREEN (-3895 5005);
DISPLAY INVISIBLE (-3895 5005);
FORCEADD OFFPAGE..2
(-3850 4700);
FORCEPROP 2 LAST $XR1 119 
J 0
(-3541 4700);
DISPLAY 0.638298 (-3541 4700);
PAINT MONO (-3541 4700);
FORCEPROP 2 LAST $XR0 184 
J 0
(-3661 4700);
DISPLAY 0.638298 (-3661 4700);
PAINT MONO (-3661 4700);
FORCEPROP 2 LAST CDS_LIB mstr_standard
J 0
(-3850 4700);
PAINT ORANGE (-3850 4700);
DISPLAY INVISIBLE (-3850 4700);
FORCEPROP 2 LAST PATH I205
J 0
(-3675 4775);
DISPLAY 1.021277 (-3675 4775);
PAINT ORANGE (-3675 4775);
DISPLAY INVISIBLE (-3675 4775);
FORCEPROP 1 LAST OFFPAGE TRUE
J 0
(-3525 4575);
DISPLAY 0.872340 (-3525 4575);
PAINT GREEN (-3525 4575);
DISPLAY INVISIBLE (-3525 4575);
FORCEPROP 1 LAST COMMENT_BODY TRUE
J 0
(-3895 4605);
DISPLAY 0.872340 (-3895 4605);
PAINT GREEN (-3895 4605);
DISPLAY INVISIBLE (-3895 4605);
FORCEADD OFFPAGE..2
(-3850 4500);
FORCEPROP 2 LAST $XR0 119 
J 0
(-3661 4500);
DISPLAY 0.638298 (-3661 4500);
PAINT MONO (-3661 4500);
FORCEPROP 2 LAST CDS_LIB mstr_standard
J 0
(-3850 4500);
PAINT ORANGE (-3850 4500);
DISPLAY INVISIBLE (-3850 4500);
FORCEPROP 2 LAST PATH I206
J 0
(-3675 4575);
DISPLAY 1.021277 (-3675 4575);
PAINT ORANGE (-3675 4575);
DISPLAY INVISIBLE (-3675 4575);
FORCEPROP 1 LAST OFFPAGE TRUE
J 0
(-3525 4375);
DISPLAY 0.872340 (-3525 4375);
PAINT GREEN (-3525 4375);
DISPLAY INVISIBLE (-3525 4375);
FORCEPROP 1 LAST COMMENT_BODY TRUE
J 0
(-3895 4405);
DISPLAY 0.872340 (-3895 4405);
PAINT GREEN (-3895 4405);
DISPLAY INVISIBLE (-3895 4405);
FORCEADD OFFPAGE..2
(-3850 4325);
FORCEPROP 2 LAST $XR0 119 
J 0
(-3661 4325);
DISPLAY 0.638298 (-3661 4325);
PAINT MONO (-3661 4325);
FORCEPROP 2 LAST CDS_LIB mstr_standard
J 0
(-3850 4325);
PAINT ORANGE (-3850 4325);
DISPLAY INVISIBLE (-3850 4325);
FORCEPROP 2 LAST PATH I208
J 0
(-3675 4400);
DISPLAY 1.021277 (-3675 4400);
PAINT ORANGE (-3675 4400);
DISPLAY INVISIBLE (-3675 4400);
FORCEPROP 1 LAST OFFPAGE TRUE
J 0
(-3525 4200);
DISPLAY 0.872340 (-3525 4200);
PAINT GREEN (-3525 4200);
DISPLAY INVISIBLE (-3525 4200);
FORCEPROP 1 LAST COMMENT_BODY TRUE
J 0
(-3895 4230);
DISPLAY 0.872340 (-3895 4230);
PAINT GREEN (-3895 4230);
DISPLAY INVISIBLE (-3895 4230);
FORCEADD RES..1
(-4700 3925);
FORCEPROP 1 LASTPIN (-4800 3925) $PN 1
J 0
(-4788 3937);
DISPLAY 0.617021 (-4788 3937);
PAINT ORANGE (-4788 3937);
FORCEPROP 1 LASTPIN (-4600 3925) $PN 2
J 0
(-4638 3937);
DISPLAY 0.617021 (-4638 3937);
PAINT ORANGE (-4638 3937);
FORCEPROP 1 LAST LOCATION R7D12
J 0
(-4750 3975);
DISPLAY 0.617021 (-4750 3975);
PAINT AQUA (-4750 3975);
FORCEPROP 1 LAST PACK_TYPE 0402
J 0
(-4300 3875);
DISPLAY 0.617021 (-4300 3875);
PAINT SKYBLUE (-4300 3875);
FORCEPROP 1 LAST MATERIAL CHIP
J 0
(-4425 3875);
DISPLAY 0.617021 (-4425 3875);
PAINT SKYBLUE (-4425 3875);
FORCEPROP 1 LAST VALUE 10.0K
J 2
(-4700 3875);
DISPLAY 0.617021 (-4700 3875);
PAINT SKYBLUE (-4700 3875);
FORCEPROP 1 LAST TOLERANCE 1%
J 0
(-4675 3875);
DISPLAY 0.617021 (-4675 3875);
PAINT SKYBLUE (-4675 3875);
FORCEPROP 1 LAST WATTAGE 1/16W
J 2
(-4450 3875);
DISPLAY 0.617021 (-4450 3875);
PAINT SKYBLUE (-4450 3875);
FORCEPROP 1 LAST PART_NUMBER G21796-016
J 0
(-4175 3875);
DISPLAY 0.617021 (-4175 3875);
PAINT BLUE (-4175 3875);
FORCEPROP 2 LAST CDS_LOCATION R7D12
J 0
(-4750 3975);
DISPLAY 0.617021 (-4750 3975);
PAINT AQUA (-4750 3975);
DISPLAY INVISIBLE (-4750 3975);
FORCEPROP 2 LAST CDS_LIB mstr_discrete
J 0
(-4700 3925);
PAINT MONO (-4700 3925);
DISPLAY INVISIBLE (-4700 3925);
FORCEPROP 0 LAST ROOM SB
J 0
(-4750 4075);
DISPLAY 1.021277 (-4750 4075);
PAINT ORANGE (-4750 4075);
DISPLAY INVISIBLE (-4750 4075);
FORCEPROP 1 LAST PATH I237
J 0
(-4750 4075);
DISPLAY 0.978723 (-4750 4075);
PAINT WHITE (-4750 4075);
DISPLAY INVISIBLE (-4750 4075);
FORCEPROP 2 LAST SEC_TYPE 0402
J 0
(-4750 4125);
DISPLAY 1.021277 (-4750 4125);
PAINT ORANGE (-4750 4125);
DISPLAY INVISIBLE (-4750 4125);
FORCEPROP 2 LAST SEC 1
J 0
(-4750 4125);
DISPLAY 0.680851 (-4750 4125);
PAINT MONO (-4750 4125);
DISPLAY INVISIBLE (-4750 4125);
FORCEADD OFFPAGE..2
(-3850 3925);
FORCEPROP 2 LAST $XR2 146 
J 0
(-3421 3925);
DISPLAY 0.638298 (-3421 3925);
PAINT MONO (-3421 3925);
FORCEPROP 2 LAST $XR1 119 
J 0
(-3541 3925);
DISPLAY 0.638298 (-3541 3925);
PAINT MONO (-3541 3925);
FORCEPROP 2 LAST $XR0 250 
J 0
(-3661 3925);
DISPLAY 0.638298 (-3661 3925);
PAINT MONO (-3661 3925);
FORCEPROP 2 LAST CDS_LIB mstr_standard
J 0
(-3850 3925);
PAINT MONO (-3850 3925);
DISPLAY INVISIBLE (-3850 3925);
FORCEPROP 2 LAST PATH I238
J 0
(-3675 4000);
DISPLAY 1.021277 (-3675 4000);
PAINT ORANGE (-3675 4000);
DISPLAY INVISIBLE (-3675 4000);
FORCEPROP 1 LAST OFFPAGE TRUE
J 0
(-3525 3800);
DISPLAY 0.872340 (-3525 3800);
PAINT GREEN (-3525 3800);
DISPLAY INVISIBLE (-3525 3800);
FORCEPROP 1 LAST COMMENT_BODY TRUE
J 0
(-3895 3830);
DISPLAY 0.872340 (-3895 3830);
PAINT GREEN (-3895 3830);
DISPLAY INVISIBLE (-3895 3830);
FORCEADD OFFPAGE..2
(-3850 3700);
FORCEPROP 2 LAST $XR3 182 
J 0
(-3301 3700);
DISPLAY 0.638298 (-3301 3700);
PAINT MONO (-3301 3700);
FORCEPROP 2 LAST $XR2 119 
J 0
(-3421 3700);
DISPLAY 0.638298 (-3421 3700);
PAINT MONO (-3421 3700);
FORCEPROP 2 LAST $XR1 146 
J 0
(-3541 3700);
DISPLAY 0.638298 (-3541 3700);
PAINT MONO (-3541 3700);
FORCEPROP 2 LAST $XR0 120 
J 0
(-3661 3700);
DISPLAY 0.638298 (-3661 3700);
PAINT MONO (-3661 3700);
FORCEPROP 2 LAST CDS_LIB mstr_standard
J 0
(-3850 3700);
PAINT MONO (-3850 3700);
DISPLAY INVISIBLE (-3850 3700);
FORCEPROP 2 LAST PATH I242
J 0
(-3675 3775);
DISPLAY 1.021277 (-3675 3775);
PAINT ORANGE (-3675 3775);
DISPLAY INVISIBLE (-3675 3775);
FORCEPROP 1 LAST OFFPAGE TRUE
J 0
(-3525 3575);
DISPLAY 0.872340 (-3525 3575);
PAINT GREEN (-3525 3575);
DISPLAY INVISIBLE (-3525 3575);
FORCEPROP 1 LAST COMMENT_BODY TRUE
J 0
(-3895 3605);
DISPLAY 0.872340 (-3895 3605);
PAINT GREEN (-3895 3605);
DISPLAY INVISIBLE (-3895 3605);
FORCEADD RES..1
(-4700 4900);
FORCEPROP 1 LASTPIN (-4600 4900) $PN 2
J 0
(-4638 4912);
DISPLAY 0.617021 (-4638 4912);
PAINT ORANGE (-4638 4912);
FORCEPROP 1 LAST PACK_TYPE 0402
J 0
(-4325 4850);
DISPLAY 0.617021 (-4325 4850);
PAINT SKYBLUE (-4325 4850);
FORCEPROP 1 LAST VALUE 4.75K
J 2
(-4775 4850);
DISPLAY 0.617021 (-4775 4850);
PAINT SKYBLUE (-4775 4850);
FORCEPROP 1 LAST PART_NUMBER G21796-072
J 0
(-4200 4850);
DISPLAY 0.617021 (-4200 4850);
PAINT BLUE (-4200 4850);
FORCEPROP 1 LAST MATERIAL CHIP
J 0
(-4450 4850);
DISPLAY 0.617021 (-4450 4850);
PAINT SKYBLUE (-4450 4850);
FORCEPROP 1 LASTPIN (-4800 4900) $PN 1
J 0
(-4788 4912);
DISPLAY 0.617021 (-4788 4912);
PAINT ORANGE (-4788 4912);
FORCEPROP 1 LAST TOLERANCE 1%
J 0
(-4725 4850);
DISPLAY 0.617021 (-4725 4850);
PAINT SKYBLUE (-4725 4850);
FORCEPROP 1 LAST LOCATION R7D3
J 0
(-4750 4950);
DISPLAY 0.617021 (-4750 4950);
PAINT AQUA (-4750 4950);
FORCEPROP 1 LAST WATTAGE 1/16W
J 2
(-4475 4850);
DISPLAY 0.617021 (-4475 4850);
PAINT SKYBLUE (-4475 4850);
FORCEPROP 0 LAST ROOM SB
J 0
(-4750 5050);
DISPLAY 1.021277 (-4750 5050);
PAINT ORANGE (-4750 5050);
DISPLAY INVISIBLE (-4750 5050);
FORCEPROP 2 LAST CDS_LOCATION R7D3
J 0
(-4750 4950);
DISPLAY 0.617021 (-4750 4950);
PAINT AQUA (-4750 4950);
DISPLAY INVISIBLE (-4750 4950);
FORCEPROP 1 LAST PATH I243
J 0
(-4750 5050);
DISPLAY 0.978723 (-4750 5050);
PAINT WHITE (-4750 5050);
DISPLAY INVISIBLE (-4750 5050);
FORCEPROP 2 LAST CDS_LIB mstr_discrete
J 0
(-4700 4900);
PAINT ORANGE (-4700 4900);
DISPLAY INVISIBLE (-4700 4900);
FORCEPROP 2 LAST SEC_TYPE 0402
J 0
(-4750 5100);
DISPLAY 1.021277 (-4750 5100);
PAINT ORANGE (-4750 5100);
DISPLAY INVISIBLE (-4750 5100);
FORCEPROP 2 LAST SEC 1
J 0
(-4750 5100);
DISPLAY 0.680851 (-4750 5100);
PAINT MONO (-4750 5100);
DISPLAY INVISIBLE (-4750 5100);
FORCEADD OFFPAGE..2
(-3850 4900);
FORCEPROP 2 LAST $XR1 119 
J 0
(-3541 4900);
DISPLAY 0.638298 (-3541 4900);
PAINT MONO (-3541 4900);
FORCEPROP 2 LAST $XR0 146 
J 0
(-3661 4900);
DISPLAY 0.638298 (-3661 4900);
PAINT MONO (-3661 4900);
FORCEPROP 2 LAST CDS_LIB mstr_standard
J 0
(-3850 4900);
PAINT ORANGE (-3850 4900);
DISPLAY INVISIBLE (-3850 4900);
FORCEPROP 2 LAST PATH I244
J 0
(-3525 4950);
DISPLAY 1.021277 (-3525 4950);
PAINT ORANGE (-3525 4950);
DISPLAY INVISIBLE (-3525 4950);
FORCEPROP 1 LAST OFFPAGE TRUE
J 0
(-3525 4775);
DISPLAY 0.872340 (-3525 4775);
PAINT GREEN (-3525 4775);
DISPLAY INVISIBLE (-3525 4775);
FORCEPROP 1 LAST COMMENT_BODY TRUE
J 0
(-3895 4805);
DISPLAY 0.872340 (-3895 4805);
PAINT GREEN (-3895 4805);
DISPLAY INVISIBLE (-3895 4805);
FORCEADD RES..1
(-4700 4125);
FORCEPROP 1 LASTPIN (-4800 4125) $PN 1
J 0
(-4788 4137);
DISPLAY 0.617021 (-4788 4137);
PAINT ORANGE (-4788 4137);
FORCEPROP 1 LAST LOCATION R7D4
J 0
(-4750 4175);
DISPLAY 0.617021 (-4750 4175);
PAINT AQUA (-4750 4175);
FORCEPROP 1 LASTPIN (-4600 4125) $PN 2
J 0
(-4638 4137);
DISPLAY 0.617021 (-4638 4137);
PAINT ORANGE (-4638 4137);
FORCEPROP 1 LAST VALUE 10.0K
J 2
(-4700 4075);
DISPLAY 0.617021 (-4700 4075);
PAINT SKYBLUE (-4700 4075);
FORCEPROP 1 LAST TOLERANCE 1%
J 0
(-4675 4075);
DISPLAY 0.617021 (-4675 4075);
PAINT SKYBLUE (-4675 4075);
FORCEPROP 1 LAST WATTAGE 1/16W
J 2
(-4450 4075);
DISPLAY 0.617021 (-4450 4075);
PAINT SKYBLUE (-4450 4075);
FORCEPROP 1 LAST MATERIAL CHIP
J 0
(-4425 4075);
DISPLAY 0.617021 (-4425 4075);
PAINT SKYBLUE (-4425 4075);
FORCEPROP 1 LAST PACK_TYPE 0402
J 0
(-4300 4075);
DISPLAY 0.617021 (-4300 4075);
PAINT SKYBLUE (-4300 4075);
FORCEPROP 1 LAST PART_NUMBER G21796-016
J 0
(-4175 4075);
DISPLAY 0.617021 (-4175 4075);
PAINT BLUE (-4175 4075);
FORCEPROP 0 LAST ROOM SB
J 0
(-4750 4275);
DISPLAY 1.021277 (-4750 4275);
PAINT ORANGE (-4750 4275);
DISPLAY INVISIBLE (-4750 4275);
FORCEPROP 2 LAST CDS_LOCATION R7D4
J 0
(-4750 4175);
DISPLAY 0.617021 (-4750 4175);
PAINT AQUA (-4750 4175);
DISPLAY INVISIBLE (-4750 4175);
FORCEPROP 1 LAST PATH I245
J 0
(-4750 4275);
DISPLAY 0.978723 (-4750 4275);
PAINT WHITE (-4750 4275);
DISPLAY INVISIBLE (-4750 4275);
FORCEPROP 2 LAST CDS_LIB mstr_discrete
J 0
(-4700 4125);
PAINT ORANGE (-4700 4125);
DISPLAY INVISIBLE (-4700 4125);
FORCEPROP 2 LAST SEC_TYPE 0402
J 0
(-4750 4325);
DISPLAY 1.021277 (-4750 4325);
PAINT ORANGE (-4750 4325);
DISPLAY INVISIBLE (-4750 4325);
FORCEPROP 2 LAST SEC 1
J 0
(-4750 4325);
DISPLAY 0.680851 (-4750 4325);
PAINT MONO (-4750 4325);
DISPLAY INVISIBLE (-4750 4325);
FORCEADD OFFPAGE..2
(-3850 4125);
FORCEPROP 2 LAST $XR0 119 
J 0
(-3661 4125);
DISPLAY 0.638298 (-3661 4125);
PAINT MONO (-3661 4125);
FORCEPROP 2 LAST CDS_LIB mstr_standard
J 0
(-3850 4125);
PAINT ORANGE (-3850 4125);
DISPLAY INVISIBLE (-3850 4125);
FORCEPROP 2 LAST PATH I246
J 0
(-3625 4175);
DISPLAY 1.021277 (-3625 4175);
PAINT ORANGE (-3625 4175);
DISPLAY INVISIBLE (-3625 4175);
FORCEPROP 1 LAST OFFPAGE TRUE
J 0
(-3525 4000);
DISPLAY 0.872340 (-3525 4000);
PAINT GREEN (-3525 4000);
DISPLAY INVISIBLE (-3525 4000);
FORCEPROP 1 LAST COMMENT_BODY TRUE
J 0
(-3895 4030);
DISPLAY 0.872340 (-3895 4030);
PAINT GREEN (-3895 4030);
DISPLAY INVISIBLE (-3895 4030);
FORCEADD RES..1
(-4650 2725);
FORCEPROP 1 LAST WATTAGE 1/16W
J 2
(-4720 2635);
DISPLAY 0.617021 (-4720 2635);
PAINT SKYBLUE (-4720 2635);
FORCEPROP 1 LAST VALUE 10.0K
J 2
(-4675 2675);
DISPLAY 0.617021 (-4675 2675);
PAINT SKYBLUE (-4675 2675);
FORCEPROP 1 LAST LOCATION R2N16
J 0
(-4800 2775);
DISPLAY 0.617021 (-4800 2775);
PAINT AQUA (-4800 2775);
FORCEPROP 1 LASTPIN (-4750 2725) $PN 1
J 0
(-4738 2737);
DISPLAY 0.617021 (-4738 2737);
PAINT MONO (-4738 2737);
FORCEPROP 1 LAST TOLERANCE 1%
J 0
(-4620 2675);
DISPLAY 0.617021 (-4620 2675);
PAINT SKYBLUE (-4620 2675);
FORCEPROP 1 LAST MATERIAL CHIP
J 0
(-4710 2635);
DISPLAY 0.617021 (-4710 2635);
PAINT SKYBLUE (-4710 2635);
FORCEPROP 1 LASTPIN (-4550 2725) $PN 2
J 0
(-4588 2737);
DISPLAY 0.617021 (-4588 2737);
PAINT MONO (-4588 2737);
FORCEPROP 1 LAST PART_NUMBER G21796-016
J 0
(-4575 2775);
DISPLAY 0.617021 (-4575 2775);
PAINT BLUE (-4575 2775);
FORCEPROP 1 LAST PACK_TYPE 0402
J 0
(-4540 2685);
DISPLAY 0.617021 (-4540 2685);
PAINT SKYBLUE (-4540 2685);
FORCEPROP 2 LAST CDS_LOCATION R2N16
J 0
(-4800 2775);
DISPLAY 0.617021 (-4800 2775);
PAINT AQUA (-4800 2775);
DISPLAY INVISIBLE (-4800 2775);
FORCEPROP 2 LAST ROOM SB
J 0
(-4650 2725);
PAINT MONO (-4650 2725);
DISPLAY INVISIBLE (-4650 2725);
FORCEPROP 2 LAST CDS_LIB mstr_discrete
J 0
(-4650 2725);
PAINT MONO (-4650 2725);
DISPLAY INVISIBLE (-4650 2725);
FORCEPROP 2 LAST BOM_COST SB
J 0
(-4700 2575);
PAINT MONO (-4700 2575);
DISPLAY INVISIBLE (-4700 2575);
FORCEPROP 2 LAST CDS_SEC 1
J 0
(-4700 2925);
DISPLAY 1.404255 (-4700 2925);
PAINT ORANGE (-4700 2925);
DISPLAY INVISIBLE (-4700 2925);
FORCEPROP 2 LAST $SEC 1
J 0
(-4700 2925);
DISPLAY 0.936170 (-4700 2925);
PAINT MONO (-4700 2925);
DISPLAY INVISIBLE (-4700 2925);
FORCEPROP 1 LAST PATH I247
J 0
(-4700 2875);
DISPLAY 0.978723 (-4700 2875);
PAINT WHITE (-4700 2875);
DISPLAY INVISIBLE (-4700 2875);
FORCEADD OFFPAGE..2
(-3700 2725);
FORCEPROP 2 LAST $XR0 119 
J 0
(-3511 2725);
DISPLAY 0.638298 (-3511 2725);
PAINT MONO (-3511 2725);
FORCEPROP 2 LAST CDS_LIB mstr_standard
J 0
(-3700 2725);
PAINT MONO (-3700 2725);
DISPLAY INVISIBLE (-3700 2725);
FORCEPROP 2 LAST PATH I248
J 0
(-3500 2775);
DISPLAY 1.021277 (-3500 2775);
PAINT ORANGE (-3500 2775);
DISPLAY INVISIBLE (-3500 2775);
FORCEPROP 2 LAST BOM_COST SB
J 0
(-3500 2775);
PAINT MONO (-3500 2775);
DISPLAY INVISIBLE (-3500 2775);
FORCEPROP 1 LAST OFFPAGE TRUE
J 0
(-3375 2600);
PAINT GREEN (-3375 2600);
DISPLAY INVISIBLE (-3375 2600);
FORCEPROP 1 LAST COMMENT_BODY TRUE
J 0
(-3745 2630);
DISPLAY 1.170213 (-3745 2630);
PAINT GREEN (-3745 2630);
DISPLAY INVISIBLE (-3745 2630);
FORCEADD P3V3_STBY..1
(-4950 2925);
FORCEPROP 3 LASTPIN (-4950 2875) SIG_NAME P3V3_STBY\g
J 0
(-4940 2885);
DISPLAY 0.659574 (-4940 2885);
PAINT MONO (-4940 2885);
DISPLAY INVISIBLE (-4940 2885);
FORCEPROP 1 LAST PATH I251
J 0
(-4905 2927);
DISPLAY 0.340426 (-4905 2927);
PAINT GREEN (-4905 2927);
DISPLAY INVISIBLE (-4905 2927);
FORCEPROP 1 LAST SIZE 1B
J 0
(-4905 2947);
DISPLAY 0.340426 (-4905 2947);
PAINT GREEN (-4905 2947);
DISPLAY INVISIBLE (-4905 2947);
FORCEPROP 2 LAST CDS_LIB mstr_symbols
J 0
(-4950 2925);
PAINT MONO (-4950 2925);
DISPLAY INVISIBLE (-4950 2925);
FORCEPROP 1 LAST VOLTAGE 3.3V
J 0
(-4995 2882);
DISPLAY 0.340426 (-4995 2882);
PAINT SKYBLUE (-4995 2882);
DISPLAY INVISIBLE (-4995 2882);
FORCEPROP 1 LAST BODY_TYPE PLUMBING
J 0
(-4995 2882);
DISPLAY 0.340426 (-4995 2882);
PAINT GREEN (-4995 2882);
DISPLAY INVISIBLE (-4995 2882);
FORCEPROP 1 LAST HDL_POWER P3V3_STBY
J 0
(-5250 2800);
DISPLAY 0.872340 (-5250 2800);
PAINT ORANGE (-5250 2800);
DISPLAY INVISIBLE (-5250 2800);
FORCEADD OFFPAGE..2
(-3925 1825);
FORCEPROP 2 LAST $XR2 119 
J 0
(-3496 1825);
DISPLAY 0.638298 (-3496 1825);
PAINT MONO (-3496 1825);
FORCEPROP 2 LAST $XR1 146 
J 0
(-3616 1825);
DISPLAY 0.638298 (-3616 1825);
PAINT MONO (-3616 1825);
FORCEPROP 2 LAST $XR0 120 
J 0
(-3736 1825);
DISPLAY 0.638298 (-3736 1825);
PAINT MONO (-3736 1825);
FORCEPROP 2 LAST CDS_LIB mstr_standard
J 0
(-3925 1825);
PAINT MONO (-3925 1825);
DISPLAY INVISIBLE (-3925 1825);
FORCEPROP 2 LAST BOM_COST SB
J 0
(-3725 1875);
PAINT MONO (-3725 1875);
DISPLAY INVISIBLE (-3725 1875);
FORCEPROP 2 LAST PATH I254
J 0
(-3475 1875);
DISPLAY 1.021277 (-3475 1875);
PAINT ORANGE (-3475 1875);
DISPLAY INVISIBLE (-3475 1875);
FORCEPROP 1 LAST OFFPAGE TRUE
J 0
(-3600 1700);
PAINT GREEN (-3600 1700);
DISPLAY INVISIBLE (-3600 1700);
FORCEPROP 1 LAST COMMENT_BODY TRUE
J 0
(-3970 1730);
DISPLAY 1.170213 (-3970 1730);
PAINT GREEN (-3970 1730);
DISPLAY INVISIBLE (-3970 1730);
FORCEADD P3V3_STBY..1
(-5075 1975);
FORCEPROP 3 LASTPIN (-5075 1925) SIG_NAME P3V3_STBY\g
J 0
(-5065 1935);
DISPLAY 0.659574 (-5065 1935);
PAINT MONO (-5065 1935);
DISPLAY INVISIBLE (-5065 1935);
FORCEPROP 1 LAST VOLTAGE 3.3V
J 0
(-5120 1932);
DISPLAY 0.340426 (-5120 1932);
PAINT SKYBLUE (-5120 1932);
DISPLAY INVISIBLE (-5120 1932);
FORCEPROP 2 LAST CDS_LIB mstr_symbols
J 0
(-5075 1975);
PAINT MONO (-5075 1975);
DISPLAY INVISIBLE (-5075 1975);
FORCEPROP 1 LAST SIZE 1B
J 0
(-5030 1997);
DISPLAY 0.340426 (-5030 1997);
PAINT GREEN (-5030 1997);
DISPLAY INVISIBLE (-5030 1997);
FORCEPROP 1 LAST PATH I256
J 0
(-5030 1977);
DISPLAY 0.340426 (-5030 1977);
PAINT GREEN (-5030 1977);
DISPLAY INVISIBLE (-5030 1977);
FORCEPROP 1 LAST BODY_TYPE PLUMBING
J 0
(-5120 1932);
DISPLAY 0.340426 (-5120 1932);
PAINT GREEN (-5120 1932);
DISPLAY INVISIBLE (-5120 1932);
FORCEPROP 1 LAST HDL_POWER P3V3_STBY
J 0
(-5375 1850);
DISPLAY 0.872340 (-5375 1850);
PAINT ORANGE (-5375 1850);
DISPLAY INVISIBLE (-5375 1850);
FORCEADD OFFPAGE..2
(-3925 1650);
FORCEPROP 2 LAST $XR3 146 
J 0
(-3406 1650);
DISPLAY 0.638298 (-3406 1650);
PAINT MONO (-3406 1650);
FORCEPROP 2 LAST $XR2 95 
J 0
(-3496 1650);
DISPLAY 0.638298 (-3496 1650);
PAINT MONO (-3496 1650);
FORCEPROP 2 LAST $XR1 170 
J 0
(-3616 1650);
DISPLAY 0.638298 (-3616 1650);
PAINT MONO (-3616 1650);
FORCEPROP 2 LAST $XR0 119 
J 0
(-3736 1650);
DISPLAY 0.638298 (-3736 1650);
PAINT MONO (-3736 1650);
FORCEPROP 2 LAST CDS_LIB mstr_standard
J 0
(-3925 1650);
PAINT MONO (-3925 1650);
DISPLAY INVISIBLE (-3925 1650);
FORCEPROP 2 LAST PATH I257
J 0
(-3750 1725);
DISPLAY 1.021277 (-3750 1725);
PAINT ORANGE (-3750 1725);
DISPLAY INVISIBLE (-3750 1725);
FORCEPROP 2 LAST BOM_COST SB
J 0
(-3725 1700);
PAINT MONO (-3725 1700);
DISPLAY INVISIBLE (-3725 1700);
FORCEPROP 1 LAST OFFPAGE TRUE
J 0
(-3600 1525);
PAINT GREEN (-3600 1525);
DISPLAY INVISIBLE (-3600 1525);
FORCEPROP 1 LAST COMMENT_BODY TRUE
J 0
(-3970 1555);
DISPLAY 1.170213 (-3970 1555);
PAINT GREEN (-3970 1555);
DISPLAY INVISIBLE (-3970 1555);
FORCEADD RES..1
(-2600 5125);
FORCEPROP 1 LAST TOLERANCE 1%
J 0
(-2570 5075);
DISPLAY 0.617021 (-2570 5075);
PAINT SKYBLUE (-2570 5075);
FORCEPROP 1 LAST WATTAGE 1/16W
J 2
(-2120 5085);
DISPLAY 0.617021 (-2120 5085);
PAINT SKYBLUE (-2120 5085);
FORCEPROP 1 LAST LOCATION R2R5
J 0
(-2825 5175);
DISPLAY 0.617021 (-2825 5175);
PAINT AQUA (-2825 5175);
FORCEPROP 1 LASTPIN (-2700 5125) $PN 1
J 0
(-2688 5137);
DISPLAY 0.617021 (-2688 5137);
PAINT ORANGE (-2688 5137);
FORCEPROP 1 LAST PART_NUMBER G21796-026
J 0
(-2500 5150);
DISPLAY 0.617021 (-2500 5150);
PAINT BLUE (-2500 5150);
FORCEPROP 1 LAST VALUE 1.00K
J 2
(-2625 5075);
DISPLAY 0.617021 (-2625 5075);
PAINT SKYBLUE (-2625 5075);
FORCEPROP 1 LASTPIN (-2500 5125) $PN 2
J 0
(-2538 5137);
DISPLAY 0.617021 (-2538 5137);
PAINT ORANGE (-2538 5137);
FORCEPROP 1 LAST PACK_TYPE 0402
J 0
(-2490 5085);
DISPLAY 0.617021 (-2490 5085);
PAINT SKYBLUE (-2490 5085);
FORCEPROP 1 LAST MATERIAL CHIP
J 0
(-2385 5085);
DISPLAY 0.617021 (-2385 5085);
PAINT SKYBLUE (-2385 5085);
FORCEPROP 2 LAST BOM_COST SB
J 0
(-2650 4975);
PAINT MONO (-2650 4975);
DISPLAY INVISIBLE (-2650 4975);
FORCEPROP 2 LAST CDS_LOCATION R2R5
J 0
(-2825 5175);
DISPLAY 0.617021 (-2825 5175);
PAINT AQUA (-2825 5175);
DISPLAY INVISIBLE (-2825 5175);
FORCEPROP 2 LAST ROOM SB
J 0
(-2600 5125);
PAINT MONO (-2600 5125);
DISPLAY INVISIBLE (-2600 5125);
FORCEPROP 2 LAST CDS_LIB mstr_discrete
J 0
(-2600 5125);
PAINT ORANGE (-2600 5125);
DISPLAY INVISIBLE (-2600 5125);
FORCEPROP 2 LAST SEC_TYPE 0402
J 0
(-2650 5325);
DISPLAY 1.021277 (-2650 5325);
PAINT ORANGE (-2650 5325);
DISPLAY INVISIBLE (-2650 5325);
FORCEPROP 2 LAST SEC 1
J 0
(-2650 5325);
DISPLAY 0.680851 (-2650 5325);
PAINT MONO (-2650 5325);
DISPLAY INVISIBLE (-2650 5325);
FORCEPROP 1 LAST PATH I258
J 0
(-2650 5275);
DISPLAY 0.978723 (-2650 5275);
PAINT WHITE (-2650 5275);
DISPLAY INVISIBLE (-2650 5275);
FORCEADD OFFPAGE..2
(-1700 5125);
FORCEPROP 2 LAST $XR1 190 
J 0
(-1391 5125);
DISPLAY 0.638298 (-1391 5125);
PAINT MONO (-1391 5125);
FORCEPROP 2 LAST $XR0 119 
J 0
(-1511 5125);
DISPLAY 0.638298 (-1511 5125);
PAINT MONO (-1511 5125);
FORCEPROP 2 LAST CDS_LIB mstr_standard
J 0
(-1700 5125);
PAINT ORANGE (-1700 5125);
DISPLAY INVISIBLE (-1700 5125);
FORCEPROP 2 LAST BOM_COST SB
J 0
(-1500 5175);
PAINT MONO (-1500 5175);
DISPLAY INVISIBLE (-1500 5175);
FORCEPROP 2 LAST PATH I259
J 0
(-1375 5175);
DISPLAY 1.021277 (-1375 5175);
PAINT ORANGE (-1375 5175);
DISPLAY INVISIBLE (-1375 5175);
FORCEPROP 1 LAST OFFPAGE TRUE
J 0
(-1375 5000);
PAINT GREEN (-1375 5000);
DISPLAY INVISIBLE (-1375 5000);
FORCEPROP 1 LAST COMMENT_BODY TRUE
J 0
(-1745 5030);
DISPLAY 1.170213 (-1745 5030);
PAINT GREEN (-1745 5030);
DISPLAY INVISIBLE (-1745 5030);
FORCEADD P3V3_STBY..1
(-2825 5350);
FORCEPROP 3 LASTPIN (-2825 5300) SIG_NAME P3V3_STBY\g
J 0
(-2815 5310);
DISPLAY 0.659574 (-2815 5310);
PAINT MONO (-2815 5310);
DISPLAY INVISIBLE (-2815 5310);
FORCEPROP 1 LAST VOLTAGE 3.3V
J 0
(-2870 5307);
DISPLAY 0.340426 (-2870 5307);
PAINT SKYBLUE (-2870 5307);
DISPLAY INVISIBLE (-2870 5307);
FORCEPROP 2 LAST CDS_LIB mstr_symbols
J 0
(-2825 5350);
PAINT MONO (-2825 5350);
DISPLAY INVISIBLE (-2825 5350);
FORCEPROP 1 LAST SIZE 1B
J 0
(-2780 5372);
DISPLAY 0.340426 (-2780 5372);
PAINT GREEN (-2780 5372);
DISPLAY INVISIBLE (-2780 5372);
FORCEPROP 1 LAST PATH I260
J 0
(-2780 5352);
DISPLAY 0.340426 (-2780 5352);
PAINT GREEN (-2780 5352);
DISPLAY INVISIBLE (-2780 5352);
FORCEPROP 1 LAST BODY_TYPE PLUMBING
J 0
(-2870 5307);
DISPLAY 0.340426 (-2870 5307);
PAINT GREEN (-2870 5307);
DISPLAY INVISIBLE (-2870 5307);
FORCEPROP 1 LAST HDL_POWER P3V3_STBY
J 0
(-3125 5225);
DISPLAY 0.872340 (-3125 5225);
PAINT ORANGE (-3125 5225);
DISPLAY INVISIBLE (-3125 5225);
FORCEADD OFFPAGE..2
(-1650 1275);
FORCEPROP 2 LAST $XR0 120 
J 0
(-1461 1275);
DISPLAY 0.638298 (-1461 1275);
PAINT MONO (-1461 1275);
FORCEPROP 2 LAST CDS_LIB mstr_standard
J 0
(-1650 1275);
PAINT MONO (-1650 1275);
DISPLAY INVISIBLE (-1650 1275);
FORCEPROP 2 LAST BOM_COST SB
J 0
(-1450 1325);
PAINT MONO (-1450 1325);
DISPLAY INVISIBLE (-1450 1325);
FORCEPROP 2 LAST PATH I264
J 0
(-1475 1350);
DISPLAY 1.021277 (-1475 1350);
PAINT ORANGE (-1475 1350);
DISPLAY INVISIBLE (-1475 1350);
FORCEPROP 1 LAST OFFPAGE TRUE
J 0
(-1325 1150);
PAINT GREEN (-1325 1150);
DISPLAY INVISIBLE (-1325 1150);
FORCEPROP 1 LAST COMMENT_BODY TRUE
J 0
(-1695 1180);
DISPLAY 1.170213 (-1695 1180);
PAINT GREEN (-1695 1180);
DISPLAY INVISIBLE (-1695 1180);
FORCEADD RES..1
(-2475 1275);
FORCEPROP 1 LASTPIN (-2575 1275) $PN 1
J 0
(-2563 1287);
DISPLAY 0.617021 (-2563 1287);
PAINT ORANGE (-2563 1287);
FORCEPROP 1 LAST LOCATION R2N9
J 0
(-2525 1325);
DISPLAY 0.617021 (-2525 1325);
PAINT AQUA (-2525 1325);
FORCEPROP 1 LAST MATERIAL CHIP
J 0
(-2425 1175);
DISPLAY 0.617021 (-2425 1175);
PAINT SKYBLUE (-2425 1175);
FORCEPROP 1 LAST PACK_TYPE 0402
J 0
(-2375 1225);
DISPLAY 0.617021 (-2375 1225);
PAINT SKYBLUE (-2375 1225);
FORCEPROP 1 LASTPIN (-2375 1275) $PN 2
J 0
(-2413 1287);
DISPLAY 0.617021 (-2413 1287);
PAINT ORANGE (-2413 1287);
FORCEPROP 1 LAST PART_NUMBER G21796-016
J 0
(-2525 1375);
DISPLAY 0.617021 (-2525 1375);
PAINT BLUE (-2525 1375);
FORCEPROP 1 LAST TOLERANCE 1%
J 0
(-2500 1200);
DISPLAY 0.617021 (-2500 1200);
PAINT SKYBLUE (-2500 1200);
FORCEPROP 1 LAST VALUE 10.0K
J 2
(-2550 1225);
DISPLAY 0.617021 (-2550 1225);
PAINT SKYBLUE (-2550 1225);
FORCEPROP 1 LAST WATTAGE 1/16W
J 2
(-2600 1175);
DISPLAY 0.617021 (-2600 1175);
PAINT SKYBLUE (-2600 1175);
FORCEPROP 2 LAST CDS_LIB mstr_discrete
J 0
(-2475 1275);
PAINT MONO (-2475 1275);
DISPLAY INVISIBLE (-2475 1275);
FORCEPROP 2 LAST SEC_TYPE 0402
J 0
(-2525 1475);
DISPLAY 1.021277 (-2525 1475);
PAINT ORANGE (-2525 1475);
DISPLAY INVISIBLE (-2525 1475);
FORCEPROP 2 LAST SEC 1
J 0
(-2525 1475);
DISPLAY 0.680851 (-2525 1475);
PAINT MONO (-2525 1475);
DISPLAY INVISIBLE (-2525 1475);
FORCEPROP 2 LAST CDS_LOCATION R2N9
J 0
(-2525 1325);
DISPLAY 0.617021 (-2525 1325);
PAINT AQUA (-2525 1325);
DISPLAY INVISIBLE (-2525 1325);
FORCEPROP 1 LAST PATH I267
J 0
(-2525 1425);
DISPLAY 0.978723 (-2525 1425);
PAINT WHITE (-2525 1425);
DISPLAY INVISIBLE (-2525 1425);
FORCEPROP 0 LAST ROOM SB
J 0
(-2425 1500);
DISPLAY 1.021277 (-2425 1500);
PAINT ORANGE (-2425 1500);
DISPLAY INVISIBLE (-2425 1500);
FORCEADD P3V3_STBY..1
(-2750 1425);
FORCEPROP 3 LASTPIN (-2750 1375) SIG_NAME P3V3_STBY\g
J 0
(-2740 1385);
DISPLAY 0.659574 (-2740 1385);
PAINT MONO (-2740 1385);
DISPLAY INVISIBLE (-2740 1385);
FORCEPROP 1 LAST VOLTAGE 3.3V
J 0
(-2795 1382);
DISPLAY 0.340426 (-2795 1382);
PAINT SKYBLUE (-2795 1382);
DISPLAY INVISIBLE (-2795 1382);
FORCEPROP 1 LAST PATH I268
J 0
(-2705 1427);
DISPLAY 0.340426 (-2705 1427);
PAINT GREEN (-2705 1427);
DISPLAY INVISIBLE (-2705 1427);
FORCEPROP 2 LAST CDS_LIB mstr_symbols
J 0
(-2750 1425);
PAINT MONO (-2750 1425);
DISPLAY INVISIBLE (-2750 1425);
FORCEPROP 1 LAST SIZE 1B
J 0
(-2705 1447);
DISPLAY 0.340426 (-2705 1447);
PAINT GREEN (-2705 1447);
DISPLAY INVISIBLE (-2705 1447);
FORCEPROP 1 LAST BODY_TYPE PLUMBING
J 0
(-2795 1382);
DISPLAY 0.340426 (-2795 1382);
PAINT GREEN (-2795 1382);
DISPLAY INVISIBLE (-2795 1382);
FORCEPROP 1 LAST HDL_POWER P3V3_STBY
J 0
(-3050 1300);
DISPLAY 0.872340 (-3050 1300);
PAINT ORANGE (-3050 1300);
DISPLAY INVISIBLE (-3050 1300);
FORCEADD OFFPAGE..2
(-3700 2400);
FORCEPROP 2 LAST $XR1 146 
J 0
(-3391 2400);
DISPLAY 0.638298 (-3391 2400);
PAINT MONO (-3391 2400);
FORCEPROP 2 LAST $XR0 119 
J 0
(-3511 2400);
DISPLAY 0.638298 (-3511 2400);
PAINT MONO (-3511 2400);
FORCEPROP 2 LAST CDS_LIB mstr_standard
J 0
(-3700 2400);
PAINT MONO (-3700 2400);
DISPLAY INVISIBLE (-3700 2400);
FORCEPROP 2 LAST PATH I279
J 0
(-3525 2475);
DISPLAY 1.021277 (-3525 2475);
PAINT ORANGE (-3525 2475);
DISPLAY INVISIBLE (-3525 2475);
FORCEPROP 2 LAST BOM_COST SB
J 0
(-3500 2450);
PAINT MONO (-3500 2450);
DISPLAY INVISIBLE (-3500 2450);
FORCEPROP 1 LAST OFFPAGE TRUE
J 0
(-3375 2275);
PAINT GREEN (-3375 2275);
DISPLAY INVISIBLE (-3375 2275);
FORCEPROP 1 LAST COMMENT_BODY TRUE
J 0
(-3745 2305);
DISPLAY 1.170213 (-3745 2305);
PAINT GREEN (-3745 2305);
DISPLAY INVISIBLE (-3745 2305);
FORCEADD RES..1
(-2575 4675);
FORCEPROP 1 LASTPIN (-2675 4675) $PN 1
J 0
(-2663 4687);
DISPLAY 0.617021 (-2663 4687);
PAINT ORANGE (-2663 4687);
FORCEPROP 1 LASTPIN (-2475 4675) $PN 2
J 0
(-2513 4687);
DISPLAY 0.617021 (-2513 4687);
PAINT ORANGE (-2513 4687);
FORCEPROP 1 LAST MATERIAL CHIP
J 0
(-2360 4635);
DISPLAY 0.617021 (-2360 4635);
PAINT SKYBLUE (-2360 4635);
FORCEPROP 1 LAST WATTAGE 1/16W
J 2
(-2095 4635);
DISPLAY 0.617021 (-2095 4635);
PAINT SKYBLUE (-2095 4635);
FORCEPROP 1 LAST PACK_TYPE 0402
J 0
(-2465 4635);
DISPLAY 0.617021 (-2465 4635);
PAINT SKYBLUE (-2465 4635);
FORCEPROP 1 LAST TOLERANCE 1%
J 0
(-2545 4625);
DISPLAY 0.617021 (-2545 4625);
PAINT SKYBLUE (-2545 4625);
FORCEPROP 1 LAST PART_NUMBER G21796-026
J 0
(-2475 4700);
DISPLAY 0.617021 (-2475 4700);
PAINT BLUE (-2475 4700);
FORCEPROP 1 LAST VALUE 1.00K
J 2
(-2600 4625);
DISPLAY 0.617021 (-2600 4625);
PAINT SKYBLUE (-2600 4625);
FORCEPROP 1 LAST LOCATION R8B23
J 0
(-2800 4725);
DISPLAY 0.617021 (-2800 4725);
PAINT AQUA (-2800 4725);
FORCEPROP 2 LAST BOM_COST SB
J 0
(-2625 4525);
PAINT MONO (-2625 4525);
DISPLAY INVISIBLE (-2625 4525);
FORCEPROP 2 LAST CDS_LOCATION R8B23
J 0
(-2800 4725);
DISPLAY 0.617021 (-2800 4725);
PAINT AQUA (-2800 4725);
DISPLAY INVISIBLE (-2800 4725);
FORCEPROP 2 LAST CDS_LIB mstr_discrete
J 0
(-2575 4675);
PAINT MONO (-2575 4675);
DISPLAY INVISIBLE (-2575 4675);
FORCEPROP 2 LAST ROOM SB
J 0
(-2575 4675);
PAINT MONO (-2575 4675);
DISPLAY INVISIBLE (-2575 4675);
FORCEPROP 1 LAST PATH I280
J 0
(-2625 4825);
DISPLAY 0.978723 (-2625 4825);
PAINT WHITE (-2625 4825);
DISPLAY INVISIBLE (-2625 4825);
FORCEPROP 2 LAST SEC 1
J 0
(-2625 4875);
DISPLAY 0.680851 (-2625 4875);
PAINT MONO (-2625 4875);
DISPLAY INVISIBLE (-2625 4875);
FORCEPROP 2 LAST SEC_TYPE 0402
J 0
(-2625 4875);
DISPLAY 1.021277 (-2625 4875);
PAINT ORANGE (-2625 4875);
DISPLAY INVISIBLE (-2625 4875);
FORCEADD OFFPAGE..2
(-1675 4675);
FORCEPROP 2 LAST $XR2 147 
J 0
(-1246 4675);
DISPLAY 0.638298 (-1246 4675);
PAINT MONO (-1246 4675);
FORCEPROP 2 LAST $XR1 119 
J 0
(-1366 4675);
DISPLAY 0.638298 (-1366 4675);
PAINT MONO (-1366 4675);
FORCEPROP 2 LAST $XR0 182 
J 0
(-1486 4675);
DISPLAY 0.638298 (-1486 4675);
PAINT MONO (-1486 4675);
FORCEPROP 2 LAST CDS_LIB mstr_standard
J 0
(-1675 4675);
PAINT MONO (-1675 4675);
DISPLAY INVISIBLE (-1675 4675);
FORCEPROP 2 LAST PATH I281
J 0
(-1500 4750);
DISPLAY 1.021277 (-1500 4750);
PAINT ORANGE (-1500 4750);
DISPLAY INVISIBLE (-1500 4750);
FORCEPROP 2 LAST BOM_COST SB
J 0
(-1475 4725);
PAINT MONO (-1475 4725);
DISPLAY INVISIBLE (-1475 4725);
FORCEPROP 1 LAST OFFPAGE TRUE
J 0
(-1350 4550);
PAINT GREEN (-1350 4550);
DISPLAY INVISIBLE (-1350 4550);
FORCEPROP 1 LAST COMMENT_BODY TRUE
J 0
(-1720 4580);
DISPLAY 1.170213 (-1720 4580);
PAINT GREEN (-1720 4580);
DISPLAY INVISIBLE (-1720 4580);
FORCEADD RES..1
(-2575 4425);
FORCEPROP 1 LAST VALUE 1.00K
J 2
(-2600 4375);
DISPLAY 0.617021 (-2600 4375);
PAINT SKYBLUE (-2600 4375);
FORCEPROP 1 LAST LOCATION R8B30
J 0
(-2800 4475);
DISPLAY 0.617021 (-2800 4475);
PAINT AQUA (-2800 4475);
FORCEPROP 1 LASTPIN (-2675 4425) $PN 1
J 0
(-2663 4437);
DISPLAY 0.617021 (-2663 4437);
PAINT ORANGE (-2663 4437);
FORCEPROP 1 LAST TOLERANCE 1%
J 0
(-2545 4375);
DISPLAY 0.617021 (-2545 4375);
PAINT SKYBLUE (-2545 4375);
FORCEPROP 1 LAST PACK_TYPE 0402
J 0
(-2465 4385);
DISPLAY 0.617021 (-2465 4385);
PAINT SKYBLUE (-2465 4385);
FORCEPROP 1 LASTPIN (-2475 4425) $PN 2
J 0
(-2513 4437);
DISPLAY 0.617021 (-2513 4437);
PAINT ORANGE (-2513 4437);
FORCEPROP 1 LAST PART_NUMBER G21796-026
J 0
(-2475 4450);
DISPLAY 0.617021 (-2475 4450);
PAINT BLUE (-2475 4450);
FORCEPROP 1 LAST WATTAGE 1/16W
J 2
(-2095 4385);
DISPLAY 0.617021 (-2095 4385);
PAINT SKYBLUE (-2095 4385);
FORCEPROP 1 LAST MATERIAL CHIP
J 0
(-2360 4385);
DISPLAY 0.617021 (-2360 4385);
PAINT SKYBLUE (-2360 4385);
FORCEPROP 2 LAST BOM_COST SB
J 0
(-2625 4275);
PAINT MONO (-2625 4275);
DISPLAY INVISIBLE (-2625 4275);
FORCEPROP 2 LAST CDS_LIB mstr_discrete
J 0
(-2575 4425);
PAINT MONO (-2575 4425);
DISPLAY INVISIBLE (-2575 4425);
FORCEPROP 2 LAST ROOM SB
J 0
(-2575 4425);
PAINT MONO (-2575 4425);
DISPLAY INVISIBLE (-2575 4425);
FORCEPROP 2 LAST CDS_LOCATION R8B30
J 0
(-2800 4475);
DISPLAY 0.617021 (-2800 4475);
PAINT AQUA (-2800 4475);
DISPLAY INVISIBLE (-2800 4475);
FORCEPROP 1 LAST PATH I282
J 0
(-2625 4575);
DISPLAY 0.978723 (-2625 4575);
PAINT WHITE (-2625 4575);
DISPLAY INVISIBLE (-2625 4575);
FORCEPROP 2 LAST SEC 1
J 0
(-2625 4625);
DISPLAY 0.680851 (-2625 4625);
PAINT MONO (-2625 4625);
DISPLAY INVISIBLE (-2625 4625);
FORCEPROP 2 LAST SEC_TYPE 0402
J 0
(-2625 4625);
DISPLAY 1.021277 (-2625 4625);
PAINT ORANGE (-2625 4625);
DISPLAY INVISIBLE (-2625 4625);
FORCEADD OFFPAGE..2
(-1675 4425);
FORCEPROP 2 LAST $XR2 147 
J 0
(-1246 4425);
DISPLAY 0.638298 (-1246 4425);
PAINT MONO (-1246 4425);
FORCEPROP 2 LAST $XR1 119 
J 0
(-1366 4425);
DISPLAY 0.638298 (-1366 4425);
PAINT MONO (-1366 4425);
FORCEPROP 2 LAST $XR0 182 
J 0
(-1486 4425);
DISPLAY 0.638298 (-1486 4425);
PAINT MONO (-1486 4425);
FORCEPROP 2 LAST CDS_LIB mstr_standard
J 0
(-1675 4425);
PAINT MONO (-1675 4425);
DISPLAY INVISIBLE (-1675 4425);
FORCEPROP 2 LAST BOM_COST SB
J 0
(-1475 4475);
PAINT MONO (-1475 4475);
DISPLAY INVISIBLE (-1475 4475);
FORCEPROP 2 LAST PATH I283
J 0
(-1500 4500);
DISPLAY 1.021277 (-1500 4500);
PAINT ORANGE (-1500 4500);
DISPLAY INVISIBLE (-1500 4500);
FORCEPROP 1 LAST OFFPAGE TRUE
J 0
(-1350 4300);
PAINT GREEN (-1350 4300);
DISPLAY INVISIBLE (-1350 4300);
FORCEPROP 1 LAST COMMENT_BODY TRUE
J 0
(-1720 4330);
DISPLAY 1.170213 (-1720 4330);
PAINT GREEN (-1720 4330);
DISPLAY INVISIBLE (-1720 4330);
FORCEADD RES..1
(-2600 4900);
FORCEPROP 1 LAST LOCATION R2M4
J 0
(-2825 4950);
DISPLAY 0.617021 (-2825 4950);
PAINT AQUA (-2825 4950);
FORCEPROP 1 LASTPIN (-2700 4900) $PN 1
J 0
(-2688 4912);
DISPLAY 0.617021 (-2688 4912);
PAINT ORANGE (-2688 4912);
FORCEPROP 1 LAST PACK_TYPE 0402
J 0
(-2490 4860);
DISPLAY 0.617021 (-2490 4860);
PAINT SKYBLUE (-2490 4860);
FORCEPROP 1 LAST MATERIAL CHIP
J 0
(-2385 4860);
DISPLAY 0.617021 (-2385 4860);
PAINT SKYBLUE (-2385 4860);
FORCEPROP 1 LASTPIN (-2500 4900) $PN 2
J 0
(-2538 4912);
DISPLAY 0.617021 (-2538 4912);
PAINT ORANGE (-2538 4912);
FORCEPROP 1 LAST VALUE 1.00K
J 2
(-2625 4850);
DISPLAY 0.617021 (-2625 4850);
PAINT SKYBLUE (-2625 4850);
FORCEPROP 1 LAST TOLERANCE 1%
J 0
(-2570 4850);
DISPLAY 0.617021 (-2570 4850);
PAINT SKYBLUE (-2570 4850);
FORCEPROP 1 LAST PART_NUMBER G21796-026
J 0
(-2500 4925);
DISPLAY 0.617021 (-2500 4925);
PAINT BLUE (-2500 4925);
FORCEPROP 1 LAST WATTAGE 1/16W
J 2
(-2120 4860);
DISPLAY 0.617021 (-2120 4860);
PAINT SKYBLUE (-2120 4860);
FORCEPROP 2 LAST CDS_LOCATION R2M4
J 0
(-2825 4950);
DISPLAY 0.617021 (-2825 4950);
PAINT AQUA (-2825 4950);
DISPLAY INVISIBLE (-2825 4950);
FORCEPROP 2 LAST BOM_COST SB
J 0
(-2650 4750);
PAINT MONO (-2650 4750);
DISPLAY INVISIBLE (-2650 4750);
FORCEPROP 1 LAST PATH I284
J 0
(-2650 5050);
DISPLAY 0.978723 (-2650 5050);
PAINT WHITE (-2650 5050);
DISPLAY INVISIBLE (-2650 5050);
FORCEPROP 2 LAST CDS_LIB mstr_discrete
J 0
(-2600 4900);
PAINT MONO (-2600 4900);
DISPLAY INVISIBLE (-2600 4900);
FORCEPROP 2 LAST ROOM SB
J 0
(-2600 4900);
PAINT MONO (-2600 4900);
DISPLAY INVISIBLE (-2600 4900);
FORCEPROP 2 LAST SEC_TYPE 0402
J 0
(-2650 5100);
DISPLAY 1.021277 (-2650 5100);
PAINT ORANGE (-2650 5100);
DISPLAY INVISIBLE (-2650 5100);
FORCEPROP 2 LAST SEC 1
J 0
(-2650 5100);
PAINT MONO (-2650 5100);
DISPLAY INVISIBLE (-2650 5100);
FORCEADD OFFPAGE..2
(-1700 4900);
FORCEPROP 2 LAST $XR2 146 
J 0
(-1271 4900);
DISPLAY 0.638298 (-1271 4900);
PAINT MONO (-1271 4900);
FORCEPROP 2 LAST $XR1 119 
J 0
(-1391 4900);
DISPLAY 0.638298 (-1391 4900);
PAINT MONO (-1391 4900);
FORCEPROP 2 LAST $XR0 199 
J 0
(-1511 4900);
DISPLAY 0.638298 (-1511 4900);
PAINT MONO (-1511 4900);
FORCEPROP 2 LAST CDS_LIB mstr_standard
J 0
(-1700 4900);
PAINT MONO (-1700 4900);
DISPLAY INVISIBLE (-1700 4900);
FORCEPROP 2 LAST BOM_COST SB
J 0
(-1500 4950);
PAINT MONO (-1500 4950);
DISPLAY INVISIBLE (-1500 4950);
FORCEPROP 2 LAST PATH I285
J 0
(-1525 4975);
DISPLAY 1.021277 (-1525 4975);
PAINT ORANGE (-1525 4975);
DISPLAY INVISIBLE (-1525 4975);
FORCEPROP 1 LAST OFFPAGE TRUE
J 0
(-1375 4775);
PAINT GREEN (-1375 4775);
DISPLAY INVISIBLE (-1375 4775);
FORCEPROP 1 LAST COMMENT_BODY TRUE
J 0
(-1745 4805);
DISPLAY 1.170213 (-1745 4805);
PAINT GREEN (-1745 4805);
DISPLAY INVISIBLE (-1745 4805);
FORCEADD RES..1
(-4800 950);
FORCEPROP 1 LAST VALUE 1.00K
J 2
(-4900 950);
DISPLAY 0.617021 (-4900 950);
PAINT SKYBLUE (-4900 950);
FORCEPROP 1 LAST WATTAGE 1/16W
J 2
(-4875 900);
DISPLAY 0.617021 (-4875 900);
PAINT SKYBLUE (-4875 900);
FORCEPROP 1 LASTPIN (-4900 950) $PN 1
J 0
(-4888 962);
DISPLAY 0.617021 (-4888 962);
PAINT ORANGE (-4888 962);
FORCEPROP 1 LAST TOLERANCE 1%
J 0
(-4650 900);
DISPLAY 0.617021 (-4650 900);
PAINT SKYBLUE (-4650 900);
FORCEPROP 1 LAST PACK_TYPE 0402
J 0
(-4675 950);
DISPLAY 0.617021 (-4675 950);
PAINT SKYBLUE (-4675 950);
FORCEPROP 1 LAST LOCATION R8C4
J 0
(-4850 1000);
DISPLAY 0.617021 (-4850 1000);
PAINT AQUA (-4850 1000);
FORCEPROP 1 LASTPIN (-4700 950) $PN 2
J 0
(-4738 962);
DISPLAY 0.617021 (-4738 962);
PAINT ORANGE (-4738 962);
FORCEPROP 1 LAST PART_NUMBER G21796-026
J 0
(-4875 900);
DISPLAY 0.617021 (-4875 900);
PAINT BLUE (-4875 900);
FORCEPROP 1 LAST MATERIAL CHIP
J 0
(-4575 900);
DISPLAY 0.617021 (-4575 900);
PAINT SKYBLUE (-4575 900);
FORCEPROP 2 LAST CDS_LIB mstr_discrete
J 0
(-4800 950);
PAINT MONO (-4800 950);
DISPLAY INVISIBLE (-4800 950);
FORCEPROP 2 LAST ROOM SB
J 0
(-4800 950);
PAINT MONO (-4800 950);
DISPLAY INVISIBLE (-4800 950);
FORCEPROP 2 LAST BOM_COST SB_PU_PD
J 0
(-4850 800);
PAINT MONO (-4850 800);
DISPLAY INVISIBLE (-4850 800);
FORCEPROP 2 LAST CDS_LOCATION R8C4
J 0
(-4850 1000);
DISPLAY 0.617021 (-4850 1000);
PAINT AQUA (-4850 1000);
DISPLAY INVISIBLE (-4850 1000);
FORCEPROP 2 LAST SEC 1
J 0
(-4850 1150);
DISPLAY 0.680851 (-4850 1150);
PAINT MONO (-4850 1150);
DISPLAY INVISIBLE (-4850 1150);
FORCEPROP 2 LAST SEC_TYPE 0402
J 0
(-4850 1150);
DISPLAY 1.021277 (-4850 1150);
PAINT ORANGE (-4850 1150);
DISPLAY INVISIBLE (-4850 1150);
FORCEPROP 1 LAST PATH I286
J 0
(-4850 1100);
DISPLAY 0.978723 (-4850 1100);
PAINT WHITE (-4850 1100);
DISPLAY INVISIBLE (-4850 1100);
FORCEADD OFFPAGE..2
(-3925 950);
FORCEPROP 2 LAST $XR2 119 
J 0
(-3496 950);
DISPLAY 0.638298 (-3496 950);
PAINT MONO (-3496 950);
FORCEPROP 2 LAST $XR1 144 
J 0
(-3616 950);
DISPLAY 0.638298 (-3616 950);
PAINT MONO (-3616 950);
FORCEPROP 2 LAST $XR0 120 
J 0
(-3736 950);
DISPLAY 0.638298 (-3736 950);
PAINT MONO (-3736 950);
FORCEPROP 2 LAST CDS_LIB mstr_standard
J 0
(-3925 950);
PAINT MONO (-3925 950);
DISPLAY INVISIBLE (-3925 950);
FORCEPROP 2 LAST BOM_COST SB
J 0
(-3725 1000);
PAINT MONO (-3725 1000);
DISPLAY INVISIBLE (-3725 1000);
FORCEPROP 2 LAST PATH I287
J 0
(-3750 1025);
DISPLAY 1.021277 (-3750 1025);
PAINT ORANGE (-3750 1025);
DISPLAY INVISIBLE (-3750 1025);
FORCEPROP 1 LAST OFFPAGE TRUE
J 0
(-3600 825);
PAINT GREEN (-3600 825);
DISPLAY INVISIBLE (-3600 825);
FORCEPROP 1 LAST COMMENT_BODY TRUE
J 0
(-3970 855);
DISPLAY 1.170213 (-3970 855);
PAINT GREEN (-3970 855);
DISPLAY INVISIBLE (-3970 855);
FORCEADD OFFPAGE..2
(-1650 1025);
FORCEPROP 2 LAST $XR2 182 
J 0
(-1221 1025);
DISPLAY 0.638298 (-1221 1025);
PAINT MONO (-1221 1025);
FORCEPROP 2 LAST $XR1 145 
J 0
(-1341 1025);
DISPLAY 0.638298 (-1341 1025);
PAINT MONO (-1341 1025);
FORCEPROP 2 LAST $XR0 120 
J 0
(-1461 1025);
DISPLAY 0.638298 (-1461 1025);
PAINT MONO (-1461 1025);
FORCEPROP 2 LAST CDS_LIB mstr_standard
J 0
(-1650 1025);
PAINT MONO (-1650 1025);
DISPLAY INVISIBLE (-1650 1025);
FORCEPROP 2 LAST BOM_COST SB
J 0
(-1450 1075);
PAINT MONO (-1450 1075);
DISPLAY INVISIBLE (-1450 1075);
FORCEPROP 2 LAST PATH I289
J 0
(-1475 1100);
DISPLAY 1.021277 (-1475 1100);
PAINT ORANGE (-1475 1100);
DISPLAY INVISIBLE (-1475 1100);
FORCEPROP 1 LAST OFFPAGE TRUE
J 0
(-1325 900);
PAINT GREEN (-1325 900);
DISPLAY INVISIBLE (-1325 900);
FORCEPROP 1 LAST COMMENT_BODY TRUE
J 0
(-1695 930);
DISPLAY 1.170213 (-1695 930);
PAINT GREEN (-1695 930);
DISPLAY INVISIBLE (-1695 930);
FORCEADD OFFPAGE..2
(1375 1075);
FORCEPROP 2 LAST $XR1 191 
J 0
(1684 1075);
DISPLAY 0.638298 (1684 1075);
PAINT MONO (1684 1075);
FORCEPROP 2 LAST $XR0 121 
J 0
(1564 1075);
DISPLAY 0.638298 (1564 1075);
PAINT MONO (1564 1075);
FORCEPROP 2 LAST CDS_LIB mstr_standard
J 0
(1375 1075);
PAINT MONO (1375 1075);
DISPLAY INVISIBLE (1375 1075);
FORCEPROP 2 LAST PATH I292
J 0
(1700 1125);
DISPLAY 1.021277 (1700 1125);
PAINT ORANGE (1700 1125);
DISPLAY INVISIBLE (1700 1125);
FORCEPROP 2 LAST BOM_COST SB
J 0
(1575 1125);
PAINT MONO (1575 1125);
DISPLAY INVISIBLE (1575 1125);
FORCEPROP 1 LAST OFFPAGE TRUE
J 0
(1700 950);
PAINT GREEN (1700 950);
DISPLAY INVISIBLE (1700 950);
FORCEPROP 1 LAST COMMENT_BODY TRUE
J 0
(1330 980);
DISPLAY 1.170213 (1330 980);
PAINT GREEN (1330 980);
DISPLAY INVISIBLE (1330 980);
FORCEADD OFFPAGE..2
(1375 1000);
FORCEPROP 2 LAST $XR1 191 
J 0
(1684 1000);
DISPLAY 0.638298 (1684 1000);
PAINT MONO (1684 1000);
FORCEPROP 2 LAST $XR0 121 
J 0
(1564 1000);
DISPLAY 0.638298 (1564 1000);
PAINT MONO (1564 1000);
FORCEPROP 2 LAST CDS_LIB mstr_standard
J 0
(1375 1000);
PAINT MONO (1375 1000);
DISPLAY INVISIBLE (1375 1000);
FORCEPROP 2 LAST PATH I293
J 0
(1700 1050);
DISPLAY 1.021277 (1700 1050);
PAINT ORANGE (1700 1050);
DISPLAY INVISIBLE (1700 1050);
FORCEPROP 2 LAST BOM_COST SB
J 0
(1575 1050);
PAINT MONO (1575 1050);
DISPLAY INVISIBLE (1575 1050);
FORCEPROP 1 LAST OFFPAGE TRUE
J 0
(1700 875);
PAINT GREEN (1700 875);
DISPLAY INVISIBLE (1700 875);
FORCEPROP 1 LAST COMMENT_BODY TRUE
J 0
(1330 905);
DISPLAY 1.170213 (1330 905);
PAINT GREEN (1330 905);
DISPLAY INVISIBLE (1330 905);
FORCEADD OFFPAGE..2
(1375 1150);
FORCEPROP 2 LAST $XR1 191 
J 0
(1684 1150);
DISPLAY 0.638298 (1684 1150);
PAINT MONO (1684 1150);
FORCEPROP 2 LAST $XR0 121 
J 0
(1564 1150);
DISPLAY 0.638298 (1564 1150);
PAINT MONO (1564 1150);
FORCEPROP 2 LAST CDS_LIB mstr_standard
J 0
(1375 1150);
PAINT MONO (1375 1150);
DISPLAY INVISIBLE (1375 1150);
FORCEPROP 2 LAST PATH I294
J 0
(1700 1200);
DISPLAY 1.021277 (1700 1200);
PAINT ORANGE (1700 1200);
DISPLAY INVISIBLE (1700 1200);
FORCEPROP 2 LAST BOM_COST SB
J 0
(1575 1200);
PAINT MONO (1575 1200);
DISPLAY INVISIBLE (1575 1200);
FORCEPROP 1 LAST OFFPAGE TRUE
J 0
(1700 1025);
PAINT GREEN (1700 1025);
DISPLAY INVISIBLE (1700 1025);
FORCEPROP 1 LAST COMMENT_BODY TRUE
J 0
(1330 1055);
DISPLAY 1.170213 (1330 1055);
PAINT GREEN (1330 1055);
DISPLAY INVISIBLE (1330 1055);
FORCEADD RES..2
(-175 1425);
FORCEPROP 1 LAST PACK_TYPE 0402
J 0
(-135 1250);
DISPLAY 0.617021 (-135 1250);
PAINT SKYBLUE (-135 1250);
FORCEPROP 1 LASTPIN (-175 1325) $PN 2
J 0
(-170 1335);
DISPLAY 0.617021 (-170 1335);
PAINT ORANGE (-170 1335);
FORCEPROP 1 LAST MATERIAL CHIP
J 0
(-135 1350);
DISPLAY 0.617021 (-135 1350);
PAINT SKYBLUE (-135 1350);
FORCEPROP 1 LAST PART_NUMBER G21796-016
J 0
(-135 1300);
DISPLAY 0.617021 (-135 1300);
PAINT BLUE (-135 1300);
FORCEPROP 1 LASTPIN (-175 1525) $PN 1
J 0
(-170 1487);
DISPLAY 0.617021 (-170 1487);
PAINT ORANGE (-170 1487);
FORCEPROP 1 LAST WATTAGE 1/16W
J 0
(-135 1400);
DISPLAY 0.617021 (-135 1400);
PAINT SKYBLUE (-135 1400);
FORCEPROP 1 LAST TOLERANCE 1%
J 0
(-130 1450);
DISPLAY 0.617021 (-130 1450);
PAINT SKYBLUE (-130 1450);
FORCEPROP 1 LAST VALUE 10.0K
J 0
(-130 1500);
DISPLAY 0.617021 (-130 1500);
PAINT SKYBLUE (-130 1500);
FORCEPROP 1 LAST LOCATION R7B6
J 0
(-130 1550);
DISPLAY 0.617021 (-130 1550);
PAINT AQUA (-130 1550);
FORCEPROP 2 LAST CDS_LIB mstr_discrete
J 0
(-175 1425);
PAINT MONO (-175 1425);
DISPLAY INVISIBLE (-175 1425);
FORCEPROP 1 LAST PATH I295
J 0
(-125 1600);
DISPLAY 0.978723 (-125 1600);
PAINT WHITE (-125 1600);
DISPLAY INVISIBLE (-125 1600);
FORCEPROP 2 LAST CDS_LOCATION R7B6
J 0
(-130 1550);
DISPLAY 0.617021 (-130 1550);
PAINT AQUA (-130 1550);
DISPLAY INVISIBLE (-130 1550);
FORCEPROP 2 LAST SEC 1
J 0
(-125 1650);
DISPLAY 0.680851 (-125 1650);
PAINT MONO (-125 1650);
DISPLAY INVISIBLE (-125 1650);
FORCEPROP 2 LAST SEC_TYPE 0402
J 0
(-125 1650);
DISPLAY 1.021277 (-125 1650);
PAINT ORANGE (-125 1650);
DISPLAY INVISIBLE (-125 1650);
FORCEPROP 0 LAST ROOM SB_PU_PD
J 0
(-225 1575);
DISPLAY 1.021277 (-225 1575);
PAINT ORANGE (-225 1575);
DISPLAY INVISIBLE (-225 1575);
FORCEADD RES..2
(-425 1425);
FORCEPROP 1 LAST PACK_TYPE 0402
J 0
(-385 1250);
DISPLAY 0.617021 (-385 1250);
PAINT SKYBLUE (-385 1250);
FORCEPROP 1 LASTPIN (-425 1325) $PN 2
J 0
(-420 1335);
DISPLAY 0.617021 (-420 1335);
PAINT ORANGE (-420 1335);
FORCEPROP 1 LASTPIN (-425 1525) $PN 1
J 0
(-420 1487);
DISPLAY 0.617021 (-420 1487);
PAINT ORANGE (-420 1487);
FORCEPROP 1 LAST MATERIAL CHIP
J 0
(-385 1350);
DISPLAY 0.617021 (-385 1350);
PAINT SKYBLUE (-385 1350);
FORCEPROP 1 LAST TOLERANCE 1%
J 0
(-380 1450);
DISPLAY 0.617021 (-380 1450);
PAINT SKYBLUE (-380 1450);
FORCEPROP 1 LAST WATTAGE 1/16W
J 0
(-385 1400);
DISPLAY 0.617021 (-385 1400);
PAINT SKYBLUE (-385 1400);
FORCEPROP 1 LAST PART_NUMBER G21796-016
J 0
(-385 1300);
DISPLAY 0.617021 (-385 1300);
PAINT BLUE (-385 1300);
FORCEPROP 1 LAST VALUE 10.0K
J 0
(-380 1500);
DISPLAY 0.617021 (-380 1500);
PAINT SKYBLUE (-380 1500);
FORCEPROP 1 LAST LOCATION R7C8
J 0
(-380 1550);
DISPLAY 0.617021 (-380 1550);
PAINT AQUA (-380 1550);
FORCEPROP 2 LAST CDS_LIB mstr_discrete
J 0
(-425 1425);
PAINT MONO (-425 1425);
DISPLAY INVISIBLE (-425 1425);
FORCEPROP 1 LAST PATH I296
J 0
(-375 1600);
DISPLAY 0.978723 (-375 1600);
PAINT WHITE (-375 1600);
DISPLAY INVISIBLE (-375 1600);
FORCEPROP 2 LAST CDS_LOCATION R7C8
J 0
(-380 1550);
DISPLAY 0.617021 (-380 1550);
PAINT AQUA (-380 1550);
DISPLAY INVISIBLE (-380 1550);
FORCEPROP 2 LAST SEC 1
J 0
(-375 1650);
DISPLAY 0.680851 (-375 1650);
PAINT MONO (-375 1650);
DISPLAY INVISIBLE (-375 1650);
FORCEPROP 2 LAST SEC_TYPE 0402
J 0
(-375 1650);
DISPLAY 1.021277 (-375 1650);
PAINT ORANGE (-375 1650);
DISPLAY INVISIBLE (-375 1650);
FORCEPROP 0 LAST ROOM SB_PU_PD
J 0
(-475 1575);
DISPLAY 1.021277 (-475 1575);
PAINT ORANGE (-475 1575);
DISPLAY INVISIBLE (-475 1575);
FORCEADD RES..2
(-650 1425);
FORCEPROP 1 LASTPIN (-650 1525) $PN 1
J 0
(-645 1487);
DISPLAY 0.617021 (-645 1487);
PAINT ORANGE (-645 1487);
FORCEPROP 1 LASTPIN (-650 1325) $PN 2
J 0
(-645 1335);
DISPLAY 0.617021 (-645 1335);
PAINT ORANGE (-645 1335);
FORCEPROP 1 LAST TOLERANCE 1%
J 0
(-605 1450);
DISPLAY 0.617021 (-605 1450);
PAINT SKYBLUE (-605 1450);
FORCEPROP 1 LAST WATTAGE 1/16W
J 0
(-610 1400);
DISPLAY 0.617021 (-610 1400);
PAINT SKYBLUE (-610 1400);
FORCEPROP 1 LAST LOCATION R7C5
J 0
(-605 1550);
DISPLAY 0.617021 (-605 1550);
PAINT AQUA (-605 1550);
FORCEPROP 1 LAST PART_NUMBER G21796-016
J 0
(-610 1300);
DISPLAY 0.617021 (-610 1300);
PAINT BLUE (-610 1300);
FORCEPROP 1 LAST VALUE 10.0K
J 0
(-605 1500);
DISPLAY 0.617021 (-605 1500);
PAINT SKYBLUE (-605 1500);
FORCEPROP 1 LAST PACK_TYPE 0402
J 0
(-610 1250);
DISPLAY 0.617021 (-610 1250);
PAINT SKYBLUE (-610 1250);
FORCEPROP 1 LAST MATERIAL CHIP
J 0
(-610 1350);
DISPLAY 0.617021 (-610 1350);
PAINT SKYBLUE (-610 1350);
FORCEPROP 2 LAST CDS_LIB mstr_discrete
J 0
(-650 1425);
PAINT MONO (-650 1425);
DISPLAY INVISIBLE (-650 1425);
FORCEPROP 0 LAST ROOM SB_PU_PD
J 0
(-700 1575);
DISPLAY 1.021277 (-700 1575);
PAINT ORANGE (-700 1575);
DISPLAY INVISIBLE (-700 1575);
FORCEPROP 2 LAST SEC_TYPE 0402
J 0
(-600 1650);
DISPLAY 1.021277 (-600 1650);
PAINT ORANGE (-600 1650);
DISPLAY INVISIBLE (-600 1650);
FORCEPROP 2 LAST SEC 1
J 0
(-600 1650);
DISPLAY 0.680851 (-600 1650);
PAINT MONO (-600 1650);
DISPLAY INVISIBLE (-600 1650);
FORCEPROP 2 LAST CDS_LOCATION R7C5
J 0
(-605 1550);
DISPLAY 0.617021 (-605 1550);
PAINT AQUA (-605 1550);
DISPLAY INVISIBLE (-605 1550);
FORCEPROP 1 LAST PATH I297
J 0
(-600 1600);
DISPLAY 0.978723 (-600 1600);
PAINT WHITE (-600 1600);
DISPLAY INVISIBLE (-600 1600);
FORCEADD P3V3_STBY..1
(-650 1850);
FORCEPROP 3 LASTPIN (-650 1800) SIG_NAME P3V3_STBY\g
J 0
(-640 1810);
DISPLAY 0.659574 (-640 1810);
PAINT MONO (-640 1810);
DISPLAY INVISIBLE (-640 1810);
FORCEPROP 1 LAST VOLTAGE 3.3V
J 0
(-695 1807);
DISPLAY 0.340426 (-695 1807);
PAINT SKYBLUE (-695 1807);
DISPLAY INVISIBLE (-695 1807);
FORCEPROP 1 LAST SIZE 1B
J 0
(-605 1872);
DISPLAY 0.340426 (-605 1872);
PAINT GREEN (-605 1872);
DISPLAY INVISIBLE (-605 1872);
FORCEPROP 2 LAST CDS_LIB mstr_symbols
J 0
(-650 1850);
PAINT MONO (-650 1850);
DISPLAY INVISIBLE (-650 1850);
FORCEPROP 1 LAST PATH I298
J 0
(-605 1852);
DISPLAY 0.340426 (-605 1852);
PAINT GREEN (-605 1852);
DISPLAY INVISIBLE (-605 1852);
FORCEPROP 1 LAST BODY_TYPE PLUMBING
J 0
(-695 1807);
DISPLAY 0.340426 (-695 1807);
PAINT GREEN (-695 1807);
DISPLAY INVISIBLE (-695 1807);
FORCEPROP 1 LAST HDL_POWER P3V3_STBY
J 0
(-950 1725);
DISPLAY 0.872340 (-950 1725);
PAINT ORANGE (-950 1725);
DISPLAY INVISIBLE (-950 1725);
FORCEADD OFFPAGE..2
(-1575 1800);
FORCEPROP 2 LAST $XR2 175 
J 0
(-1146 1800);
DISPLAY 0.638298 (-1146 1800);
PAINT MONO (-1146 1800);
FORCEPROP 2 LAST $XR1 146 
J 0
(-1266 1800);
DISPLAY 0.638298 (-1266 1800);
PAINT MONO (-1266 1800);
FORCEPROP 2 LAST $XR0 120 
J 0
(-1386 1800);
DISPLAY 0.638298 (-1386 1800);
PAINT MONO (-1386 1800);
FORCEPROP 2 LAST CDS_LIB mstr_standard
J 0
(-1575 1800);
PAINT MONO (-1575 1800);
DISPLAY INVISIBLE (-1575 1800);
FORCEPROP 2 LAST PATH I299
J 0
(-1400 1875);
DISPLAY 1.021277 (-1400 1875);
PAINT ORANGE (-1400 1875);
DISPLAY INVISIBLE (-1400 1875);
FORCEPROP 2 LAST BOM_COST SB
J 0
(-1250 1850);
PAINT MONO (-1250 1850);
DISPLAY INVISIBLE (-1250 1850);
FORCEPROP 1 LAST OFFPAGE TRUE
J 0
(-1250 1675);
PAINT GREEN (-1250 1675);
DISPLAY INVISIBLE (-1250 1675);
FORCEPROP 1 LAST COMMENT_BODY TRUE
J 0
(-1620 1705);
DISPLAY 1.170213 (-1620 1705);
PAINT GREEN (-1620 1705);
DISPLAY INVISIBLE (-1620 1705);
FORCEADD P3V3_STBY..1
(-2800 2050);
FORCEPROP 3 LASTPIN (-2800 2000) SIG_NAME P3V3_STBY\g
J 0
(-2790 2010);
DISPLAY 0.659574 (-2790 2010);
PAINT MONO (-2790 2010);
DISPLAY INVISIBLE (-2790 2010);
FORCEPROP 1 LAST VOLTAGE 3.3V
J 0
(-2845 2007);
DISPLAY 0.340426 (-2845 2007);
PAINT SKYBLUE (-2845 2007);
DISPLAY INVISIBLE (-2845 2007);
FORCEPROP 1 LAST PATH I300
J 0
(-2755 2052);
DISPLAY 0.340426 (-2755 2052);
PAINT GREEN (-2755 2052);
DISPLAY INVISIBLE (-2755 2052);
FORCEPROP 1 LAST SIZE 1B
J 0
(-2755 2072);
DISPLAY 0.340426 (-2755 2072);
PAINT GREEN (-2755 2072);
DISPLAY INVISIBLE (-2755 2072);
FORCEPROP 2 LAST CDS_LIB mstr_symbols
J 0
(-2800 2050);
PAINT MONO (-2800 2050);
DISPLAY INVISIBLE (-2800 2050);
FORCEPROP 1 LAST BODY_TYPE PLUMBING
J 0
(-2845 2007);
DISPLAY 0.340426 (-2845 2007);
PAINT GREEN (-2845 2007);
DISPLAY INVISIBLE (-2845 2007);
FORCEPROP 1 LAST HDL_POWER P3V3_STBY
J 0
(-3100 1925);
DISPLAY 0.872340 (-3100 1925);
PAINT ORANGE (-3100 1925);
DISPLAY INVISIBLE (-3100 1925);
FORCEADD RES..1
(-2475 1800);
FORCEPROP 1 LAST VALUE 4.75K
J 2
(-2500 1700);
DISPLAY 0.617021 (-2500 1700);
PAINT SKYBLUE (-2500 1700);
FORCEPROP 1 LASTPIN (-2575 1800) $PN 1
J 0
(-2563 1812);
DISPLAY 0.617021 (-2563 1812);
PAINT ORANGE (-2563 1812);
FORCEPROP 1 LASTPIN (-2375 1800) $PN 2
J 0
(-2413 1812);
DISPLAY 0.617021 (-2413 1812);
PAINT ORANGE (-2413 1812);
FORCEPROP 1 LAST LOCATION R8D14
J 0
(-2525 1850);
DISPLAY 0.617021 (-2525 1850);
PAINT AQUA (-2525 1850);
FORCEPROP 1 LAST PART_NUMBER G21796-072
J 0
(-2525 1900);
DISPLAY 0.617021 (-2525 1900);
PAINT BLUE (-2525 1900);
FORCEPROP 1 LAST WATTAGE 1/16W
J 2
(-2500 1650);
DISPLAY 0.617021 (-2500 1650);
PAINT SKYBLUE (-2500 1650);
FORCEPROP 1 LAST MATERIAL CHIP
J 0
(-2475 1650);
DISPLAY 0.617021 (-2475 1650);
PAINT SKYBLUE (-2475 1650);
FORCEPROP 1 LAST TOLERANCE 1%
J 0
(-2475 1700);
DISPLAY 0.617021 (-2475 1700);
PAINT SKYBLUE (-2475 1700);
FORCEPROP 1 LAST PACK_TYPE 0402
J 0
(-2225 1650);
DISPLAY 0.617021 (-2225 1650);
PAINT SKYBLUE (-2225 1650);
FORCEPROP 2 LAST BOM_COST SB
J 0
(-2525 1650);
PAINT MONO (-2525 1650);
DISPLAY INVISIBLE (-2525 1650);
FORCEPROP 2 LAST CDS_LIB mstr_discrete
J 0
(-2475 1800);
PAINT ORANGE (-2475 1800);
DISPLAY INVISIBLE (-2475 1800);
FORCEPROP 2 LAST ROOM SB
J 0
(-2475 1800);
PAINT MONO (-2475 1800);
DISPLAY INVISIBLE (-2475 1800);
FORCEPROP 2 LAST SEC_TYPE 0402
J 0
(-2525 2000);
DISPLAY 1.021277 (-2525 2000);
PAINT ORANGE (-2525 2000);
DISPLAY INVISIBLE (-2525 2000);
FORCEPROP 2 LAST SEC 1
J 0
(-2525 2000);
DISPLAY 0.680851 (-2525 2000);
PAINT MONO (-2525 2000);
DISPLAY INVISIBLE (-2525 2000);
FORCEPROP 1 LAST PATH I301
J 0
(-2525 1950);
DISPLAY 0.978723 (-2525 1950);
PAINT WHITE (-2525 1950);
DISPLAY INVISIBLE (-2525 1950);
FORCEPROP 2 LAST CDS_LOCATION R8D14
J 0
(-2525 1850);
DISPLAY 0.617021 (-2525 1850);
PAINT AQUA (-2525 1850);
DISPLAY INVISIBLE (-2525 1850);
FORCEADD P3V3_STBY..1
(-4950 5225);
FORCEPROP 3 LASTPIN (-4950 5175) SIG_NAME P3V3_STBY\g
J 0
(-4940 5185);
DISPLAY 0.659574 (-4940 5185);
PAINT MONO (-4940 5185);
DISPLAY INVISIBLE (-4940 5185);
FORCEPROP 1 LAST PATH I302
J 0
(-4905 5227);
DISPLAY 0.340426 (-4905 5227);
PAINT GREEN (-4905 5227);
DISPLAY INVISIBLE (-4905 5227);
FORCEPROP 2 LAST CDS_LIB mstr_symbols
J 0
(-4950 5225);
PAINT MONO (-4950 5225);
DISPLAY INVISIBLE (-4950 5225);
FORCEPROP 1 LAST SIZE 1B
J 0
(-4905 5247);
DISPLAY 0.340426 (-4905 5247);
PAINT GREEN (-4905 5247);
DISPLAY INVISIBLE (-4905 5247);
FORCEPROP 1 LAST VOLTAGE 3.3V
J 0
(-4995 5182);
DISPLAY 0.340426 (-4995 5182);
PAINT SKYBLUE (-4995 5182);
DISPLAY INVISIBLE (-4995 5182);
FORCEPROP 1 LAST BODY_TYPE PLUMBING
J 0
(-4995 5182);
DISPLAY 0.340426 (-4995 5182);
PAINT GREEN (-4995 5182);
DISPLAY INVISIBLE (-4995 5182);
FORCEPROP 1 LAST HDL_POWER P3V3_STBY
J 0
(-5250 5100);
DISPLAY 0.872340 (-5250 5100);
PAINT ORANGE (-5250 5100);
DISPLAY INVISIBLE (-5250 5100);
FORCEADD RES..1
(-4675 2400);
FORCEPROP 1 LAST WATTAGE 1/16W
J 2
(-4750 2350);
DISPLAY 0.617021 (-4750 2350);
PAINT SKYBLUE (-4750 2350);
FORCEPROP 1 LASTPIN (-4775 2400) $PN 1
J 0
(-4763 2412);
DISPLAY 0.617021 (-4763 2412);
PAINT ORANGE (-4763 2412);
FORCEPROP 1 LAST PACK_TYPE 0402
J 0
(-4850 2425);
DISPLAY 0.617021 (-4850 2425);
PAINT SKYBLUE (-4850 2425);
FORCEPROP 1 LAST LOCATION R8C6
J 0
(-4725 2450);
DISPLAY 0.617021 (-4725 2450);
PAINT AQUA (-4725 2450);
FORCEPROP 1 LASTPIN (-4575 2400) $PN 2
J 0
(-4613 2412);
DISPLAY 0.617021 (-4613 2412);
PAINT ORANGE (-4613 2412);
FORCEPROP 1 LAST TOLERANCE 1%
J 0
(-4575 2350);
DISPLAY 0.617021 (-4575 2350);
PAINT SKYBLUE (-4575 2350);
FORCEPROP 1 LAST VALUE 4.75K
J 2
(-4475 2450);
DISPLAY 0.617021 (-4475 2450);
PAINT SKYBLUE (-4475 2450);
FORCEPROP 1 LAST PART_NUMBER G21796-072
J 0
(-4475 2425);
DISPLAY 0.617021 (-4475 2425);
PAINT BLUE (-4475 2425);
FORCEPROP 1 LAST MATERIAL CHIP
J 0
(-4500 2350);
DISPLAY 0.617021 (-4500 2350);
PAINT SKYBLUE (-4500 2350);
FORCEPROP 2 LAST CDS_LOCATION R8C6
J 0
(-4725 2450);
DISPLAY 0.617021 (-4725 2450);
PAINT AQUA (-4725 2450);
DISPLAY INVISIBLE (-4725 2450);
FORCEPROP 2 LAST CDS_LIB mstr_discrete
J 0
(-4675 2400);
PAINT MONO (-4675 2400);
DISPLAY INVISIBLE (-4675 2400);
FORCEPROP 2 LAST ROOM SB_PU_PD
J 0
(-4725 2500);
DISPLAY 1.021277 (-4725 2500);
PAINT ORANGE (-4725 2500);
DISPLAY INVISIBLE (-4725 2500);
FORCEPROP 1 LAST PATH I303
J 0
(-4725 2550);
DISPLAY 0.978723 (-4725 2550);
PAINT WHITE (-4725 2550);
DISPLAY INVISIBLE (-4725 2550);
FORCEPROP 2 LAST SEC 1
J 0
(-4725 2600);
DISPLAY 0.680851 (-4725 2600);
PAINT MONO (-4725 2600);
DISPLAY INVISIBLE (-4725 2600);
FORCEPROP 2 LAST SEC_TYPE 0402
J 0
(-4725 2600);
DISPLAY 1.021277 (-4725 2600);
PAINT ORANGE (-4725 2600);
DISPLAY INVISIBLE (-4725 2600);
FORCEADD RES..1
(-4800 1825);
FORCEPROP 1 LAST TOLERANCE 1%
J 0
(-4650 1775);
DISPLAY 0.617021 (-4650 1775);
PAINT SKYBLUE (-4650 1775);
FORCEPROP 1 LAST PACK_TYPE 0402
J 0
(-4675 1825);
DISPLAY 0.617021 (-4675 1825);
PAINT SKYBLUE (-4675 1825);
FORCEPROP 1 LAST VALUE 4.75K
J 2
(-4900 1825);
DISPLAY 0.617021 (-4900 1825);
PAINT SKYBLUE (-4900 1825);
FORCEPROP 1 LASTPIN (-4700 1825) $PN 2
J 0
(-4738 1837);
DISPLAY 0.617021 (-4738 1837);
PAINT ORANGE (-4738 1837);
FORCEPROP 1 LAST PART_NUMBER G21796-072
J 0
(-4875 1775);
DISPLAY 0.617021 (-4875 1775);
PAINT BLUE (-4875 1775);
FORCEPROP 1 LASTPIN (-4900 1825) $PN 1
J 0
(-4888 1837);
DISPLAY 0.617021 (-4888 1837);
PAINT ORANGE (-4888 1837);
FORCEPROP 1 LAST LOCATION R8C2
J 0
(-4850 1875);
DISPLAY 0.617021 (-4850 1875);
PAINT AQUA (-4850 1875);
FORCEPROP 1 LAST MATERIAL CHIP
J 0
(-4575 1775);
DISPLAY 0.617021 (-4575 1775);
PAINT SKYBLUE (-4575 1775);
FORCEPROP 1 LAST WATTAGE 1/16W
J 2
(-4875 1775);
DISPLAY 0.617021 (-4875 1775);
PAINT SKYBLUE (-4875 1775);
FORCEPROP 2 LAST CDS_LOCATION R8C2
J 0
(-4850 1875);
DISPLAY 0.617021 (-4850 1875);
PAINT AQUA (-4850 1875);
DISPLAY INVISIBLE (-4850 1875);
FORCEPROP 2 LAST CDS_LIB mstr_discrete
J 0
(-4800 1825);
PAINT MONO (-4800 1825);
DISPLAY INVISIBLE (-4800 1825);
FORCEPROP 1 LAST PATH I304
J 0
(-4850 1975);
DISPLAY 0.978723 (-4850 1975);
PAINT WHITE (-4850 1975);
DISPLAY INVISIBLE (-4850 1975);
FORCEPROP 2 LAST ROOM SB_PU_PD
J 0
(-4850 1925);
DISPLAY 1.021277 (-4850 1925);
PAINT ORANGE (-4850 1925);
DISPLAY INVISIBLE (-4850 1925);
FORCEPROP 2 LAST SEC_TYPE 0402
J 0
(-4850 2025);
DISPLAY 1.021277 (-4850 2025);
PAINT ORANGE (-4850 2025);
DISPLAY INVISIBLE (-4850 2025);
FORCEPROP 2 LAST SEC 1
J 0
(-4850 2025);
DISPLAY 0.680851 (-4850 2025);
PAINT MONO (-4850 2025);
DISPLAY INVISIBLE (-4850 2025);
FORCEADD RES..1
(-4700 3700);
FORCEPROP 1 LAST LOCATION R7D6
J 0
(-4750 3750);
DISPLAY 0.617021 (-4750 3750);
PAINT AQUA (-4750 3750);
FORCEPROP 1 LAST VALUE 4.75K
J 2
(-4700 3650);
DISPLAY 0.617021 (-4700 3650);
PAINT SKYBLUE (-4700 3650);
FORCEPROP 1 LASTPIN (-4800 3700) $PN 1
J 0
(-4788 3712);
DISPLAY 0.617021 (-4788 3712);
PAINT ORANGE (-4788 3712);
FORCEPROP 1 LASTPIN (-4600 3700) $PN 2
J 0
(-4638 3712);
DISPLAY 0.617021 (-4638 3712);
PAINT ORANGE (-4638 3712);
FORCEPROP 1 LAST TOLERANCE 1%
J 0
(-4675 3650);
DISPLAY 0.617021 (-4675 3650);
PAINT SKYBLUE (-4675 3650);
FORCEPROP 1 LAST PACK_TYPE 0402
J 0
(-4300 3650);
DISPLAY 0.617021 (-4300 3650);
PAINT SKYBLUE (-4300 3650);
FORCEPROP 1 LAST WATTAGE 1/16W
J 2
(-4450 3650);
DISPLAY 0.617021 (-4450 3650);
PAINT SKYBLUE (-4450 3650);
FORCEPROP 1 LAST MATERIAL CHIP
J 0
(-4425 3650);
DISPLAY 0.617021 (-4425 3650);
PAINT SKYBLUE (-4425 3650);
FORCEPROP 1 LAST PART_NUMBER G21796-072
J 0
(-4175 3650);
DISPLAY 0.617021 (-4175 3650);
PAINT BLUE (-4175 3650);
FORCEPROP 1 LAST PATH I306
J 0
(-4750 3850);
DISPLAY 0.978723 (-4750 3850);
PAINT WHITE (-4750 3850);
DISPLAY INVISIBLE (-4750 3850);
FORCEPROP 2 LAST SEC_TYPE 0402
J 0
(-4750 3900);
DISPLAY 1.021277 (-4750 3900);
PAINT ORANGE (-4750 3900);
DISPLAY INVISIBLE (-4750 3900);
FORCEPROP 2 LAST SEC 1
J 0
(-4750 3900);
DISPLAY 0.680851 (-4750 3900);
PAINT MONO (-4750 3900);
DISPLAY INVISIBLE (-4750 3900);
FORCEPROP 2 LAST ROOM SB_PU_PD
J 0
(-4750 3800);
DISPLAY 1.021277 (-4750 3800);
PAINT ORANGE (-4750 3800);
DISPLAY INVISIBLE (-4750 3800);
FORCEPROP 2 LAST CDS_LIB mstr_discrete
J 0
(-4700 3700);
PAINT MONO (-4700 3700);
DISPLAY INVISIBLE (-4700 3700);
FORCEPROP 2 LAST CDS_LOCATION R7D6
J 0
(-4750 3750);
DISPLAY 0.617021 (-4750 3750);
PAINT AQUA (-4750 3750);
DISPLAY INVISIBLE (-4750 3750);
FORCEADD RES..1
(-4800 1650);
FORCEPROP 1 LASTPIN (-4900 1650) $PN 1
J 0
(-4888 1662);
DISPLAY 0.617021 (-4888 1662);
PAINT ORANGE (-4888 1662);
FORCEPROP 1 LASTPIN (-4700 1650) $PN 2
J 0
(-4738 1662);
DISPLAY 0.617021 (-4738 1662);
PAINT ORANGE (-4738 1662);
FORCEPROP 1 LAST TOLERANCE 1%
J 0
(-4650 1600);
DISPLAY 0.617021 (-4650 1600);
PAINT SKYBLUE (-4650 1600);
FORCEPROP 1 LAST WATTAGE 1/16W
J 2
(-4875 1600);
DISPLAY 0.617021 (-4875 1600);
PAINT SKYBLUE (-4875 1600);
FORCEPROP 1 LAST VALUE 4.75K
J 2
(-4900 1650);
DISPLAY 0.617021 (-4900 1650);
PAINT SKYBLUE (-4900 1650);
FORCEPROP 1 LAST LOCATION R8B31
J 0
(-4850 1700);
DISPLAY 0.617021 (-4850 1700);
PAINT AQUA (-4850 1700);
FORCEPROP 1 LAST PACK_TYPE 0402
J 0
(-4675 1650);
DISPLAY 0.617021 (-4675 1650);
PAINT SKYBLUE (-4675 1650);
FORCEPROP 1 LAST MATERIAL CHIP
J 0
(-4575 1600);
DISPLAY 0.617021 (-4575 1600);
PAINT SKYBLUE (-4575 1600);
FORCEPROP 1 LAST PART_NUMBER G21796-072
J 0
(-4875 1600);
DISPLAY 0.617021 (-4875 1600);
PAINT BLUE (-4875 1600);
FORCEPROP 2 LAST CDS_LOCATION R8B31
J 0
(-4850 1700);
DISPLAY 0.617021 (-4850 1700);
PAINT AQUA (-4850 1700);
DISPLAY INVISIBLE (-4850 1700);
FORCEPROP 2 LAST CDS_LIB mstr_discrete
J 0
(-4800 1650);
PAINT MONO (-4800 1650);
DISPLAY INVISIBLE (-4800 1650);
FORCEPROP 2 LAST ROOM SB_PU_PD
J 0
(-4850 1750);
DISPLAY 1.021277 (-4850 1750);
PAINT ORANGE (-4850 1750);
DISPLAY INVISIBLE (-4850 1750);
FORCEPROP 1 LAST PATH I307
J 0
(-4850 1800);
DISPLAY 0.978723 (-4850 1800);
PAINT WHITE (-4850 1800);
DISPLAY INVISIBLE (-4850 1800);
FORCEPROP 2 LAST SEC 1
J 0
(-4850 1850);
DISPLAY 0.680851 (-4850 1850);
PAINT MONO (-4850 1850);
DISPLAY INVISIBLE (-4850 1850);
FORCEPROP 2 LAST SEC_TYPE 0402
J 0
(-4850 1850);
DISPLAY 1.021277 (-4850 1850);
PAINT ORANGE (-4850 1850);
DISPLAY INVISIBLE (-4850 1850);
FORCEADD RES..1
(-2475 1025);
FORCEPROP 1 LAST TOLERANCE 1%
J 0
(-2375 975);
DISPLAY 0.617021 (-2375 975);
PAINT SKYBLUE (-2375 975);
FORCEPROP 1 LAST VALUE 4.75K
J 2
(-2250 1075);
DISPLAY 0.617021 (-2250 1075);
PAINT SKYBLUE (-2250 1075);
FORCEPROP 1 LAST MATERIAL CHIP
J 0
(-2300 975);
DISPLAY 0.617021 (-2300 975);
PAINT SKYBLUE (-2300 975);
FORCEPROP 1 LAST PART_NUMBER G21796-072
J 0
(-2550 950);
DISPLAY 0.617021 (-2550 950);
PAINT BLUE (-2550 950);
FORCEPROP 1 LAST WATTAGE 1/16W
J 2
(-2550 975);
DISPLAY 0.617021 (-2550 975);
PAINT SKYBLUE (-2550 975);
FORCEPROP 1 LAST PACK_TYPE 0402
J 0
(-2650 1050);
DISPLAY 0.617021 (-2650 1050);
PAINT SKYBLUE (-2650 1050);
FORCEPROP 1 LASTPIN (-2575 1025) $PN 1
J 0
(-2563 1037);
DISPLAY 0.617021 (-2563 1037);
PAINT ORANGE (-2563 1037);
FORCEPROP 1 LAST LOCATION R2N7
J 0
(-2525 1075);
DISPLAY 0.617021 (-2525 1075);
PAINT AQUA (-2525 1075);
FORCEPROP 1 LASTPIN (-2375 1025) $PN 2
J 0
(-2413 1037);
DISPLAY 0.617021 (-2413 1037);
PAINT ORANGE (-2413 1037);
FORCEPROP 1 LAST PATH I309
J 0
(-2525 1175);
DISPLAY 0.978723 (-2525 1175);
PAINT WHITE (-2525 1175);
DISPLAY INVISIBLE (-2525 1175);
FORCEPROP 2 LAST CDS_LOCATION R2N7
J 0
(-2525 1075);
DISPLAY 0.617021 (-2525 1075);
PAINT AQUA (-2525 1075);
DISPLAY INVISIBLE (-2525 1075);
FORCEPROP 2 LAST SEC 1
J 0
(-2525 1225);
DISPLAY 0.680851 (-2525 1225);
PAINT MONO (-2525 1225);
DISPLAY INVISIBLE (-2525 1225);
FORCEPROP 2 LAST CDS_LIB mstr_discrete
J 0
(-2475 1025);
PAINT MONO (-2475 1025);
DISPLAY INVISIBLE (-2475 1025);
FORCEPROP 2 LAST SEC_TYPE 0402
J 0
(-2525 1225);
DISPLAY 1.021277 (-2525 1225);
PAINT ORANGE (-2525 1225);
DISPLAY INVISIBLE (-2525 1225);
FORCEPROP 2 LAST ROOM SB_PU_PD
J 0
(-2525 1125);
DISPLAY 1.021277 (-2525 1125);
PAINT ORANGE (-2525 1125);
DISPLAY INVISIBLE (-2525 1125);
FORCEADD OFFPAGE..2
(625 5100);
FORCEPROP 2 LAST $XR0 121 
J 0
(814 5100);
DISPLAY 0.638298 (814 5100);
PAINT MONO (814 5100);
FORCEPROP 2 LAST CDS_LIB mstr_standard
J 0
(625 5100);
PAINT MONO (625 5100);
DISPLAY INVISIBLE (625 5100);
FORCEPROP 2 LAST PATH I311
J 0
(800 5175);
DISPLAY 1.021277 (800 5175);
PAINT ORANGE (800 5175);
DISPLAY INVISIBLE (800 5175);
FORCEPROP 2 LAST BOM_COST SB
J 0
(825 5150);
PAINT MONO (825 5150);
DISPLAY INVISIBLE (825 5150);
FORCEPROP 1 LAST OFFPAGE TRUE
J 0
(950 4975);
PAINT GREEN (950 4975);
DISPLAY INVISIBLE (950 4975);
FORCEPROP 1 LAST COMMENT_BODY TRUE
J 0
(580 5005);
DISPLAY 1.170213 (580 5005);
PAINT GREEN (580 5005);
DISPLAY INVISIBLE (580 5005);
FORCEADD OFFPAGE..2
(625 4875);
FORCEPROP 2 LAST $XR0 121 
J 0
(814 4875);
DISPLAY 0.638298 (814 4875);
PAINT MONO (814 4875);
FORCEPROP 2 LAST CDS_LIB mstr_standard
J 0
(625 4875);
PAINT MONO (625 4875);
DISPLAY INVISIBLE (625 4875);
FORCEPROP 2 LAST PATH I312
J 0
(800 4950);
DISPLAY 1.021277 (800 4950);
PAINT ORANGE (800 4950);
DISPLAY INVISIBLE (800 4950);
FORCEPROP 2 LAST BOM_COST SB
J 0
(825 4925);
PAINT MONO (825 4925);
DISPLAY INVISIBLE (825 4925);
FORCEPROP 1 LAST OFFPAGE TRUE
J 0
(950 4750);
PAINT GREEN (950 4750);
DISPLAY INVISIBLE (950 4750);
FORCEPROP 1 LAST COMMENT_BODY TRUE
J 0
(580 4780);
DISPLAY 1.170213 (580 4780);
PAINT GREEN (580 4780);
DISPLAY INVISIBLE (580 4780);
FORCEADD OFFPAGE..2
(625 4650);
FORCEPROP 2 LAST $XR0 121 
J 0
(814 4650);
DISPLAY 0.638298 (814 4650);
PAINT MONO (814 4650);
FORCEPROP 2 LAST CDS_LIB mstr_standard
J 0
(625 4650);
PAINT MONO (625 4650);
DISPLAY INVISIBLE (625 4650);
FORCEPROP 2 LAST PATH I313
J 0
(800 4725);
DISPLAY 1.021277 (800 4725);
PAINT ORANGE (800 4725);
DISPLAY INVISIBLE (800 4725);
FORCEPROP 2 LAST BOM_COST SB
J 0
(825 4700);
PAINT MONO (825 4700);
DISPLAY INVISIBLE (825 4700);
FORCEPROP 1 LAST OFFPAGE TRUE
J 0
(950 4525);
PAINT GREEN (950 4525);
DISPLAY INVISIBLE (950 4525);
FORCEPROP 1 LAST COMMENT_BODY TRUE
J 0
(580 4555);
DISPLAY 1.170213 (580 4555);
PAINT GREEN (580 4555);
DISPLAY INVISIBLE (580 4555);
FORCEADD OFFPAGE..2
(625 4400);
FORCEPROP 2 LAST $XR0 121 
J 0
(814 4400);
DISPLAY 0.638298 (814 4400);
PAINT MONO (814 4400);
FORCEPROP 2 LAST CDS_LIB mstr_standard
J 0
(625 4400);
PAINT MONO (625 4400);
DISPLAY INVISIBLE (625 4400);
FORCEPROP 2 LAST PATH I314
J 0
(800 4475);
DISPLAY 1.021277 (800 4475);
PAINT ORANGE (800 4475);
DISPLAY INVISIBLE (800 4475);
FORCEPROP 2 LAST BOM_COST SB
J 0
(825 4450);
PAINT MONO (825 4450);
DISPLAY INVISIBLE (825 4450);
FORCEPROP 1 LAST OFFPAGE TRUE
J 0
(950 4275);
PAINT GREEN (950 4275);
DISPLAY INVISIBLE (950 4275);
FORCEPROP 1 LAST COMMENT_BODY TRUE
J 0
(580 4305);
DISPLAY 1.170213 (580 4305);
PAINT GREEN (580 4305);
DISPLAY INVISIBLE (580 4305);
FORCEADD OFFPAGE..2
(625 4175);
FORCEPROP 2 LAST $XR0 121 
J 0
(814 4175);
DISPLAY 0.638298 (814 4175);
PAINT MONO (814 4175);
FORCEPROP 2 LAST CDS_LIB mstr_standard
J 0
(625 4175);
PAINT MONO (625 4175);
DISPLAY INVISIBLE (625 4175);
FORCEPROP 2 LAST PATH I319
J 0
(800 4250);
DISPLAY 1.021277 (800 4250);
PAINT ORANGE (800 4250);
DISPLAY INVISIBLE (800 4250);
FORCEPROP 2 LAST BOM_COST SB
J 0
(825 4225);
PAINT MONO (825 4225);
DISPLAY INVISIBLE (825 4225);
FORCEPROP 1 LAST OFFPAGE TRUE
J 0
(950 4050);
PAINT GREEN (950 4050);
DISPLAY INVISIBLE (950 4050);
FORCEPROP 1 LAST COMMENT_BODY TRUE
J 0
(580 4080);
DISPLAY 1.170213 (580 4080);
PAINT GREEN (580 4080);
DISPLAY INVISIBLE (580 4080);
FORCEADD OFFPAGE..2
(625 3925);
FORCEPROP 2 LAST $XR1 121 
J 0
(934 3925);
DISPLAY 0.638298 (934 3925);
PAINT MONO (934 3925);
FORCEPROP 2 LAST $XR0 109 
J 0
(814 3925);
DISPLAY 0.638298 (814 3925);
PAINT MONO (814 3925);
FORCEPROP 2 LAST CDS_LIB mstr_standard
J 0
(625 3925);
PAINT MONO (625 3925);
DISPLAY INVISIBLE (625 3925);
FORCEPROP 2 LAST PATH I320
J 0
(800 4000);
DISPLAY 1.021277 (800 4000);
PAINT ORANGE (800 4000);
DISPLAY INVISIBLE (800 4000);
FORCEPROP 2 LAST BOM_COST SB
J 0
(825 3975);
PAINT MONO (825 3975);
DISPLAY INVISIBLE (825 3975);
FORCEPROP 1 LAST OFFPAGE TRUE
J 0
(950 3800);
PAINT GREEN (950 3800);
DISPLAY INVISIBLE (950 3800);
FORCEPROP 1 LAST COMMENT_BODY TRUE
J 0
(580 3830);
DISPLAY 1.170213 (580 3830);
PAINT GREEN (580 3830);
DISPLAY INVISIBLE (580 3830);
FORCEADD RES..1
(-375 3925);
FORCEPROP 1 LAST TOLERANCE 1%
J 0
(-345 3875);
DISPLAY 0.617021 (-345 3875);
PAINT SKYBLUE (-345 3875);
FORCEPROP 1 LASTPIN (-275 3925) $PN 2
J 0
(-313 3937);
DISPLAY 0.617021 (-313 3937);
PAINT ORANGE (-313 3937);
FORCEPROP 1 LAST VALUE 1.00K
J 2
(-400 3875);
DISPLAY 0.617021 (-400 3875);
PAINT SKYBLUE (-400 3875);
FORCEPROP 1 LAST LOCATION R3P8
J 0
(-400 3975);
DISPLAY 0.617021 (-400 3975);
PAINT AQUA (-400 3975);
FORCEPROP 1 LAST PART_NUMBER G21796-026
J 0
(-275 3950);
DISPLAY 0.617021 (-275 3950);
PAINT BLUE (-275 3950);
FORCEPROP 1 LAST WATTAGE 1/16W
J 2
(105 3885);
DISPLAY 0.617021 (105 3885);
PAINT SKYBLUE (105 3885);
FORCEPROP 1 LAST MATERIAL CHIP
J 0
(-160 3885);
DISPLAY 0.617021 (-160 3885);
PAINT SKYBLUE (-160 3885);
FORCEPROP 1 LAST PACK_TYPE 0402
J 0
(-265 3885);
DISPLAY 0.617021 (-265 3885);
PAINT SKYBLUE (-265 3885);
FORCEPROP 1 LASTPIN (-475 3925) $PN 1
J 0
(-463 3937);
DISPLAY 0.617021 (-463 3937);
PAINT ORANGE (-463 3937);
FORCEPROP 2 LAST BOM_COST SB
J 0
(-425 3775);
PAINT MONO (-425 3775);
DISPLAY INVISIBLE (-425 3775);
FORCEPROP 2 LAST CDS_LOCATION R3P8
J 0
(-400 3975);
DISPLAY 0.617021 (-400 3975);
PAINT AQUA (-400 3975);
DISPLAY INVISIBLE (-400 3975);
FORCEPROP 2 LAST CDS_LIB mstr_discrete
J 0
(-375 3925);
PAINT MONO (-375 3925);
DISPLAY INVISIBLE (-375 3925);
FORCEPROP 2 LAST ROOM SB
J 0
(-375 3925);
PAINT MONO (-375 3925);
DISPLAY INVISIBLE (-375 3925);
FORCEPROP 1 LAST PATH I322
J 0
(-425 4075);
DISPLAY 0.978723 (-425 4075);
PAINT WHITE (-425 4075);
DISPLAY INVISIBLE (-425 4075);
FORCEPROP 2 LAST SEC 1
J 0
(-425 4125);
DISPLAY 0.680851 (-425 4125);
PAINT MONO (-425 4125);
DISPLAY INVISIBLE (-425 4125);
FORCEPROP 2 LAST SEC_TYPE 0402
J 0
(-425 4125);
DISPLAY 1.021277 (-425 4125);
PAINT ORANGE (-425 4125);
DISPLAY INVISIBLE (-425 4125);
FORCEADD OFFPAGE..2
(-3925 1300);
FORCEPROP 2 LAST $XR2 147 
J 0
(-3496 1300);
DISPLAY 0.638298 (-3496 1300);
PAINT MONO (-3496 1300);
FORCEPROP 2 LAST $XR1 119 
J 0
(-3616 1300);
DISPLAY 0.638298 (-3616 1300);
PAINT MONO (-3616 1300);
FORCEPROP 2 LAST $XR0 108 
J 0
(-3736 1300);
DISPLAY 0.638298 (-3736 1300);
PAINT MONO (-3736 1300);
FORCEPROP 2 LAST CDS_LIB mstr_standard
J 0
(-3925 1300);
PAINT MONO (-3925 1300);
DISPLAY INVISIBLE (-3925 1300);
FORCEPROP 2 LAST BOM_COST SB
J 0
(-3725 1350);
PAINT MONO (-3725 1350);
DISPLAY INVISIBLE (-3725 1350);
FORCEPROP 2 LAST PATH I325
J 0
(-3750 1375);
DISPLAY 1.021277 (-3750 1375);
PAINT ORANGE (-3750 1375);
DISPLAY INVISIBLE (-3750 1375);
FORCEPROP 1 LAST OFFPAGE TRUE
J 0
(-3600 1175);
PAINT GREEN (-3600 1175);
DISPLAY INVISIBLE (-3600 1175);
FORCEPROP 1 LAST COMMENT_BODY TRUE
J 0
(-3970 1205);
DISPLAY 1.170213 (-3970 1205);
PAINT GREEN (-3970 1205);
DISPLAY INVISIBLE (-3970 1205);
FORCEADD RES..1
(-4800 1300);
FORCEPROP 1 LASTPIN (-4900 1300) $PN 1
J 0
(-4888 1312);
DISPLAY 0.617021 (-4888 1312);
PAINT ORANGE (-4888 1312);
FORCEPROP 1 LASTPIN (-4700 1300) $PN 2
J 0
(-4738 1312);
DISPLAY 0.617021 (-4738 1312);
PAINT ORANGE (-4738 1312);
FORCEPROP 1 LAST TOLERANCE 1%
J 0
(-4650 1250);
DISPLAY 0.617021 (-4650 1250);
PAINT SKYBLUE (-4650 1250);
FORCEPROP 1 LAST PACK_TYPE 0402
J 0
(-4675 1300);
DISPLAY 0.617021 (-4675 1300);
PAINT SKYBLUE (-4675 1300);
FORCEPROP 1 LAST MATERIAL CHIP
J 0
(-4575 1250);
DISPLAY 0.617021 (-4575 1250);
PAINT SKYBLUE (-4575 1250);
FORCEPROP 1 LAST WATTAGE 1/16W
J 2
(-4875 1250);
DISPLAY 0.617021 (-4875 1250);
PAINT SKYBLUE (-4875 1250);
FORCEPROP 1 LAST VALUE 4.75K
J 2
(-4900 1300);
DISPLAY 0.617021 (-4900 1300);
PAINT SKYBLUE (-4900 1300);
FORCEPROP 1 LAST LOCATION R8C1
J 0
(-4850 1350);
DISPLAY 0.617021 (-4850 1350);
PAINT AQUA (-4850 1350);
FORCEPROP 1 LAST PART_NUMBER G21796-072
J 0
(-4875 1250);
DISPLAY 0.617021 (-4875 1250);
PAINT BLUE (-4875 1250);
FORCEPROP 2 LAST CDS_LOCATION R8C1
J 0
(-4850 1350);
DISPLAY 0.617021 (-4850 1350);
PAINT AQUA (-4850 1350);
DISPLAY INVISIBLE (-4850 1350);
FORCEPROP 2 LAST CDS_LIB mstr_discrete
J 0
(-4800 1300);
PAINT MONO (-4800 1300);
DISPLAY INVISIBLE (-4800 1300);
FORCEPROP 2 LAST ROOM SB_PU_PD
J 0
(-4850 1400);
DISPLAY 1.021277 (-4850 1400);
PAINT ORANGE (-4850 1400);
DISPLAY INVISIBLE (-4850 1400);
FORCEPROP 1 LAST PATH I326
J 0
(-4850 1450);
DISPLAY 0.978723 (-4850 1450);
PAINT WHITE (-4850 1450);
DISPLAY INVISIBLE (-4850 1450);
FORCEPROP 2 LAST SEC 1
J 0
(-4850 1500);
DISPLAY 0.680851 (-4850 1500);
PAINT MONO (-4850 1500);
DISPLAY INVISIBLE (-4850 1500);
FORCEPROP 2 LAST SEC_TYPE 0402
J 0
(-4850 1500);
DISPLAY 1.021277 (-4850 1500);
PAINT ORANGE (-4850 1500);
DISPLAY INVISIBLE (-4850 1500);
FORCEADD RES..1
(-4800 1125);
FORCEPROP 1 LAST VALUE 4.75K
J 2
(-4900 1125);
DISPLAY 0.617021 (-4900 1125);
PAINT SKYBLUE (-4900 1125);
FORCEPROP 1 LAST WATTAGE 1/16W
J 2
(-4875 1075);
DISPLAY 0.617021 (-4875 1075);
PAINT SKYBLUE (-4875 1075);
FORCEPROP 1 LASTPIN (-4900 1125) $PN 1
J 0
(-4888 1137);
DISPLAY 0.617021 (-4888 1137);
PAINT ORANGE (-4888 1137);
FORCEPROP 1 LASTPIN (-4700 1125) $PN 2
J 0
(-4738 1137);
DISPLAY 0.617021 (-4738 1137);
PAINT ORANGE (-4738 1137);
FORCEPROP 1 LAST LOCATION R8C7
J 0
(-4850 1175);
DISPLAY 0.617021 (-4850 1175);
PAINT AQUA (-4850 1175);
FORCEPROP 1 LAST TOLERANCE 1%
J 0
(-4650 1075);
DISPLAY 0.617021 (-4650 1075);
PAINT SKYBLUE (-4650 1075);
FORCEPROP 1 LAST MATERIAL CHIP
J 0
(-4575 1075);
DISPLAY 0.617021 (-4575 1075);
PAINT SKYBLUE (-4575 1075);
FORCEPROP 1 LAST PACK_TYPE 0402
J 0
(-4675 1125);
DISPLAY 0.617021 (-4675 1125);
PAINT SKYBLUE (-4675 1125);
FORCEPROP 1 LAST PART_NUMBER G21796-072
J 0
(-4875 1075);
DISPLAY 0.617021 (-4875 1075);
PAINT BLUE (-4875 1075);
FORCEPROP 2 LAST BOM_COST SB
J 0
(-4850 975);
PAINT MONO (-4850 975);
DISPLAY INVISIBLE (-4850 975);
FORCEPROP 2 LAST CDS_LOCATION R8C7
J 0
(-4850 1175);
DISPLAY 0.617021 (-4850 1175);
PAINT AQUA (-4850 1175);
DISPLAY INVISIBLE (-4850 1175);
FORCEPROP 2 LAST CDS_LIB mstr_discrete
J 0
(-4800 1125);
PAINT MONO (-4800 1125);
DISPLAY INVISIBLE (-4800 1125);
FORCEPROP 2 LAST ROOM SB_PU_PD
J 0
(-4800 1125);
PAINT MONO (-4800 1125);
DISPLAY INVISIBLE (-4800 1125);
FORCEPROP 1 LAST PATH I327
J 0
(-4850 1275);
DISPLAY 0.978723 (-4850 1275);
PAINT WHITE (-4850 1275);
DISPLAY INVISIBLE (-4850 1275);
FORCEPROP 2 LAST SEC_TYPE 0402
J 0
(-4850 1325);
DISPLAY 1.021277 (-4850 1325);
PAINT ORANGE (-4850 1325);
DISPLAY INVISIBLE (-4850 1325);
FORCEPROP 2 LAST SEC 1
J 0
(-4850 1325);
DISPLAY 0.680851 (-4850 1325);
PAINT MONO (-4850 1325);
DISPLAY INVISIBLE (-4850 1325);
FORCEADD OFFPAGE..2
(-3925 1125);
FORCEPROP 2 LAST $XR2 147 
J 0
(-3496 1125);
DISPLAY 0.638298 (-3496 1125);
PAINT MONO (-3496 1125);
FORCEPROP 2 LAST $XR1 119 
J 0
(-3616 1125);
DISPLAY 0.638298 (-3616 1125);
PAINT MONO (-3616 1125);
FORCEPROP 2 LAST $XR0 108 
J 0
(-3736 1125);
DISPLAY 0.638298 (-3736 1125);
PAINT MONO (-3736 1125);
FORCEPROP 2 LAST CDS_LIB mstr_standard
J 0
(-3925 1125);
PAINT MONO (-3925 1125);
DISPLAY INVISIBLE (-3925 1125);
FORCEPROP 2 LAST PATH I328
J 0
(-3750 1200);
DISPLAY 1.021277 (-3750 1200);
PAINT ORANGE (-3750 1200);
DISPLAY INVISIBLE (-3750 1200);
FORCEPROP 2 LAST BOM_COST SB
J 0
(-3725 1175);
PAINT MONO (-3725 1175);
DISPLAY INVISIBLE (-3725 1175);
FORCEPROP 1 LAST OFFPAGE TRUE
J 0
(-3600 1000);
PAINT GREEN (-3600 1000);
DISPLAY INVISIBLE (-3600 1000);
FORCEPROP 1 LAST COMMENT_BODY TRUE
J 0
(-3970 1030);
DISPLAY 1.170213 (-3970 1030);
PAINT GREEN (-3970 1030);
DISPLAY INVISIBLE (-3970 1030);
FORCEADD RES..1
(-4700 4700);
FORCEPROP 1 LAST PACK_TYPE 0402
J 0
(-4325 4650);
DISPLAY 0.617021 (-4325 4650);
PAINT SKYBLUE (-4325 4650);
FORCEPROP 1 LAST MATERIAL CHIP
J 0
(-4450 4650);
DISPLAY 0.617021 (-4450 4650);
PAINT SKYBLUE (-4450 4650);
FORCEPROP 1 LAST PART_NUMBER G21796-026
J 0
(-4200 4650);
DISPLAY 0.617021 (-4200 4650);
PAINT BLUE (-4200 4650);
FORCEPROP 1 LAST TOLERANCE 1%
J 0
(-4725 4650);
DISPLAY 0.617021 (-4725 4650);
PAINT SKYBLUE (-4725 4650);
FORCEPROP 1 LAST VALUE 1.00K
J 2
(-4775 4650);
DISPLAY 0.617021 (-4775 4650);
PAINT SKYBLUE (-4775 4650);
FORCEPROP 1 LAST LOCATION R7D7
J 0
(-4750 4750);
DISPLAY 0.617021 (-4750 4750);
PAINT AQUA (-4750 4750);
FORCEPROP 1 LAST WATTAGE 1/16W
J 2
(-4475 4650);
DISPLAY 0.617021 (-4475 4650);
PAINT SKYBLUE (-4475 4650);
FORCEPROP 1 LASTPIN (-4800 4700) $PN 1
J 0
(-4788 4712);
DISPLAY 0.617021 (-4788 4712);
PAINT ORANGE (-4788 4712);
FORCEPROP 1 LASTPIN (-4600 4700) $PN 2
J 0
(-4638 4712);
DISPLAY 0.617021 (-4638 4712);
PAINT ORANGE (-4638 4712);
FORCEPROP 2 LAST BOM_COST SB_PU_PD
J 0
(-4750 4550);
PAINT MONO (-4750 4550);
DISPLAY INVISIBLE (-4750 4550);
FORCEPROP 2 LAST CDS_LOCATION R7D7
J 0
(-4750 4750);
DISPLAY 0.617021 (-4750 4750);
PAINT AQUA (-4750 4750);
DISPLAY INVISIBLE (-4750 4750);
FORCEPROP 2 LAST CDS_LIB mstr_discrete
J 0
(-4700 4700);
PAINT ORANGE (-4700 4700);
DISPLAY INVISIBLE (-4700 4700);
FORCEPROP 2 LAST ROOM SB
J 0
(-4700 4700);
PAINT MONO (-4700 4700);
DISPLAY INVISIBLE (-4700 4700);
FORCEPROP 1 LAST PATH I331
J 0
(-4750 4850);
DISPLAY 0.978723 (-4750 4850);
PAINT WHITE (-4750 4850);
DISPLAY INVISIBLE (-4750 4850);
FORCEPROP 2 LAST SEC_TYPE 0402
J 0
(-4750 4900);
DISPLAY 1.021277 (-4750 4900);
PAINT ORANGE (-4750 4900);
DISPLAY INVISIBLE (-4750 4900);
FORCEPROP 2 LAST SEC 1
J 0
(-4750 4900);
DISPLAY 0.680851 (-4750 4900);
PAINT MONO (-4750 4900);
DISPLAY INVISIBLE (-4750 4900);
FORCEADD RES..1
(-4700 5100);
FORCEPROP 1 LASTPIN (-4600 5100) $PN 2
J 0
(-4638 5112);
DISPLAY 0.617021 (-4638 5112);
PAINT ORANGE (-4638 5112);
FORCEPROP 1 LAST PART_NUMBER G21796-026
J 0
(-4200 5050);
DISPLAY 0.617021 (-4200 5050);
PAINT BLUE (-4200 5050);
FORCEPROP 1 LAST PACK_TYPE 0402
J 0
(-4325 5050);
DISPLAY 0.617021 (-4325 5050);
PAINT SKYBLUE (-4325 5050);
FORCEPROP 1 LAST MATERIAL CHIP
J 0
(-4450 5050);
DISPLAY 0.617021 (-4450 5050);
PAINT SKYBLUE (-4450 5050);
FORCEPROP 1 LAST LOCATION R7D2
J 0
(-4750 5150);
DISPLAY 0.617021 (-4750 5150);
PAINT AQUA (-4750 5150);
FORCEPROP 1 LASTPIN (-4800 5100) $PN 1
J 0
(-4788 5112);
DISPLAY 0.617021 (-4788 5112);
PAINT ORANGE (-4788 5112);
FORCEPROP 1 LAST WATTAGE 1/16W
J 2
(-4475 5050);
DISPLAY 0.617021 (-4475 5050);
PAINT SKYBLUE (-4475 5050);
FORCEPROP 1 LAST VALUE 1.00K
J 2
(-4775 5050);
DISPLAY 0.617021 (-4775 5050);
PAINT SKYBLUE (-4775 5050);
FORCEPROP 1 LAST TOLERANCE 1%
J 0
(-4725 5050);
DISPLAY 0.617021 (-4725 5050);
PAINT SKYBLUE (-4725 5050);
FORCEPROP 2 LAST BOM_COST SB_PU_PD
J 0
(-4750 4950);
PAINT MONO (-4750 4950);
DISPLAY INVISIBLE (-4750 4950);
FORCEPROP 2 LAST ROOM SB
J 0
(-4700 5100);
PAINT MONO (-4700 5100);
DISPLAY INVISIBLE (-4700 5100);
FORCEPROP 2 LAST CDS_LIB mstr_discrete
J 0
(-4700 5100);
PAINT ORANGE (-4700 5100);
DISPLAY INVISIBLE (-4700 5100);
FORCEPROP 1 LAST PATH I332
J 0
(-4750 5250);
DISPLAY 0.978723 (-4750 5250);
PAINT WHITE (-4750 5250);
DISPLAY INVISIBLE (-4750 5250);
FORCEPROP 2 LAST CDS_LOCATION R7D2
J 0
(-4750 5150);
DISPLAY 0.617021 (-4750 5150);
PAINT AQUA (-4750 5150);
DISPLAY INVISIBLE (-4750 5150);
FORCEPROP 2 LAST SEC 1
J 0
(-4750 5300);
DISPLAY 0.680851 (-4750 5300);
PAINT MONO (-4750 5300);
DISPLAY INVISIBLE (-4750 5300);
FORCEPROP 2 LAST SEC_TYPE 0402
J 0
(-4750 5300);
DISPLAY 1.021277 (-4750 5300);
PAINT ORANGE (-4750 5300);
DISPLAY INVISIBLE (-4750 5300);
FORCEADD RES..1
(-2500 3150);
FORCEPROP 1 LASTPIN (-2400 3150) $PN 2
J 0
(-2438 3162);
DISPLAY 0.617021 (-2438 3162);
PAINT ORANGE (-2438 3162);
FORCEPROP 1 LAST PACK_TYPE 0402
J 0
(-2375 3150);
DISPLAY 0.617021 (-2375 3150);
PAINT SKYBLUE (-2375 3150);
FORCEPROP 1 LAST VALUE 4.75K
J 2
(-2600 3150);
DISPLAY 0.617021 (-2600 3150);
PAINT SKYBLUE (-2600 3150);
FORCEPROP 1 LASTPIN (-2600 3150) $PN 1
J 0
(-2588 3162);
DISPLAY 0.617021 (-2588 3162);
PAINT ORANGE (-2588 3162);
FORCEPROP 1 LAST LOCATION R8C25
J 0
(-2550 3200);
DISPLAY 0.617021 (-2550 3200);
PAINT AQUA (-2550 3200);
FORCEPROP 1 LAST WATTAGE 1/16W
J 2
(-2625 3100);
DISPLAY 0.617021 (-2625 3100);
PAINT SKYBLUE (-2625 3100);
FORCEPROP 1 LAST TOLERANCE 1%
J 0
(-2350 3100);
DISPLAY 0.617021 (-2350 3100);
PAINT SKYBLUE (-2350 3100);
FORCEPROP 1 LAST PART_NUMBER G21796-072
J 0
(-2575 3100);
DISPLAY 0.617021 (-2575 3100);
PAINT BLUE (-2575 3100);
FORCEPROP 1 LAST MATERIAL CHIP
J 0
(-2275 3100);
DISPLAY 0.617021 (-2275 3100);
PAINT SKYBLUE (-2275 3100);
FORCEPROP 2 LAST CDS_LOCATION R8C25
J 0
(-2550 3200);
DISPLAY 0.617021 (-2550 3200);
PAINT AQUA (-2550 3200);
DISPLAY INVISIBLE (-2550 3200);
FORCEPROP 2 LAST ROOM SB_PU_PD
J 0
(-2550 3250);
DISPLAY 1.021277 (-2550 3250);
PAINT ORANGE (-2550 3250);
DISPLAY INVISIBLE (-2550 3250);
FORCEPROP 2 LAST CDS_LIB mstr_discrete
J 0
(-2500 3150);
PAINT ORANGE (-2500 3150);
DISPLAY INVISIBLE (-2500 3150);
FORCEPROP 1 LAST PATH I333
J 0
(-2550 3300);
DISPLAY 0.978723 (-2550 3300);
PAINT WHITE (-2550 3300);
DISPLAY INVISIBLE (-2550 3300);
FORCEPROP 2 LAST SEC_TYPE 0402
J 0
(-2550 3350);
DISPLAY 1.021277 (-2550 3350);
PAINT ORANGE (-2550 3350);
DISPLAY INVISIBLE (-2550 3350);
FORCEPROP 2 LAST SEC 1
J 0
(-2550 3350);
DISPLAY 0.680851 (-2550 3350);
PAINT MONO (-2550 3350);
DISPLAY INVISIBLE (-2550 3350);
FORCEADD OFFPAGE..2
(-1600 3150);
FORCEPROP 2 LAST $XR2 145 
J 0
(-1171 3150);
DISPLAY 0.638298 (-1171 3150);
PAINT MONO (-1171 3150);
FORCEPROP 2 LAST $XR1 119 
J 0
(-1291 3150);
DISPLAY 0.638298 (-1291 3150);
PAINT MONO (-1291 3150);
FORCEPROP 2 LAST $XR0 120 
J 0
(-1411 3150);
DISPLAY 0.638298 (-1411 3150);
PAINT MONO (-1411 3150);
FORCEPROP 2 LAST CDS_LIB mstr_standard
J 0
(-1600 3150);
PAINT ORANGE (-1600 3150);
DISPLAY INVISIBLE (-1600 3150);
FORCEPROP 2 LAST BOM_COST SB
J 0
(-1400 3200);
PAINT MONO (-1400 3200);
DISPLAY INVISIBLE (-1400 3200);
FORCEPROP 2 LAST PATH I334
J 0
(-1425 3225);
DISPLAY 1.021277 (-1425 3225);
PAINT ORANGE (-1425 3225);
DISPLAY INVISIBLE (-1425 3225);
FORCEPROP 1 LAST OFFPAGE TRUE
J 0
(-1275 3025);
PAINT GREEN (-1275 3025);
DISPLAY INVISIBLE (-1275 3025);
FORCEPROP 1 LAST COMMENT_BODY TRUE
J 0
(-1645 3055);
DISPLAY 1.170213 (-1645 3055);
PAINT GREEN (-1645 3055);
DISPLAY INVISIBLE (-1645 3055);
FORCEADD P3V3_STBY..1
(-2775 3425);
FORCEPROP 3 LASTPIN (-2775 3375) SIG_NAME P3V3_STBY\g
J 0
(-2765 3385);
DISPLAY 0.659574 (-2765 3385);
PAINT MONO (-2765 3385);
DISPLAY INVISIBLE (-2765 3385);
FORCEPROP 1 LAST VOLTAGE 3.3V
J 0
(-2820 3382);
DISPLAY 0.340426 (-2820 3382);
PAINT SKYBLUE (-2820 3382);
DISPLAY INVISIBLE (-2820 3382);
FORCEPROP 2 LAST CDS_LIB mstr_symbols
J 0
(-2775 3425);
PAINT ORANGE (-2775 3425);
DISPLAY INVISIBLE (-2775 3425);
FORCEPROP 1 LAST SIZE 1B
J 0
(-2730 3447);
DISPLAY 0.340426 (-2730 3447);
PAINT GREEN (-2730 3447);
DISPLAY INVISIBLE (-2730 3447);
FORCEPROP 1 LAST PATH I335
J 0
(-2730 3427);
DISPLAY 0.340426 (-2730 3427);
PAINT GREEN (-2730 3427);
DISPLAY INVISIBLE (-2730 3427);
FORCEPROP 1 LAST BODY_TYPE PLUMBING
J 0
(-2820 3382);
DISPLAY 0.340426 (-2820 3382);
PAINT GREEN (-2820 3382);
DISPLAY INVISIBLE (-2820 3382);
FORCEPROP 1 LAST HDL_POWER P3V3_STBY
J 0
(-3075 3300);
DISPLAY 0.872340 (-3075 3300);
PAINT ORANGE (-3075 3300);
DISPLAY INVISIBLE (-3075 3300);
FORCEADD P1V05_PCH_STBY..1
(-625 5325);
FORCEPROP 3 LASTPIN (-625 5275) SIG_NAME P1V05_PCH_STBY\g
J 0
(-615 5285);
DISPLAY 0.659574 (-615 5285);
PAINT MONO (-615 5285);
DISPLAY INVISIBLE (-615 5285);
FORCEPROP 1 LAST PATH I339
J 0
(-575 5350);
DISPLAY 0.872340 (-575 5350);
PAINT AQUA (-575 5350);
DISPLAY INVISIBLE (-575 5350);
FORCEPROP 2 LAST CDS_LIB mstr_symbols
J 0
(-625 5325);
PAINT ORANGE (-625 5325);
DISPLAY INVISIBLE (-625 5325);
FORCEPROP 1 LAST VOLTAGE 1.05V
J 0
(-670 5282);
DISPLAY 0.340426 (-670 5282);
PAINT SKYBLUE (-670 5282);
DISPLAY INVISIBLE (-670 5282);
FORCEPROP 1 LAST BODY_TYPE PLUMBING
J 0
(-670 5282);
DISPLAY 0.340426 (-670 5282);
PAINT GREEN (-670 5282);
DISPLAY INVISIBLE (-670 5282);
FORCEPROP 1 LAST HDL_POWER P1V05_PCH_STBY
J 0
(-625 5375);
DISPLAY 0.872340 (-625 5375);
PAINT GREEN (-625 5375);
DISPLAY INVISIBLE (-625 5375);
FORCEADD OFFPAGE..2
(-1575 2700);
FORCEPROP 2 LAST $XR1 145 
J 0
(-1266 2700);
DISPLAY 0.638298 (-1266 2700);
PAINT MONO (-1266 2700);
FORCEPROP 2 LAST $XR0 120 
J 0
(-1386 2700);
DISPLAY 0.638298 (-1386 2700);
PAINT MONO (-1386 2700);
FORCEPROP 2 LAST CDS_LIB mstr_standard
J 0
(-1575 2700);
PAINT ORANGE (-1575 2700);
DISPLAY INVISIBLE (-1575 2700);
FORCEPROP 2 LAST PATH I340
J 0
(-1400 2775);
DISPLAY 1.021277 (-1400 2775);
PAINT ORANGE (-1400 2775);
DISPLAY INVISIBLE (-1400 2775);
FORCEPROP 2 LAST BOM_COST SB
J 0
(-1250 2750);
PAINT MONO (-1250 2750);
DISPLAY INVISIBLE (-1250 2750);
FORCEPROP 1 LAST OFFPAGE TRUE
J 0
(-1250 2575);
PAINT GREEN (-1250 2575);
DISPLAY INVISIBLE (-1250 2575);
FORCEPROP 1 LAST COMMENT_BODY TRUE
J 0
(-1620 2605);
DISPLAY 1.170213 (-1620 2605);
PAINT GREEN (-1620 2605);
DISPLAY INVISIBLE (-1620 2605);
FORCEADD RES..1
(-2475 2700);
FORCEPROP 1 LASTPIN (-2575 2700) $PN 1
J 0
(-2563 2712);
DISPLAY 0.617021 (-2563 2712);
PAINT ORANGE (-2563 2712);
FORCEPROP 1 LAST LOCATION R2N32
J 0
(-2525 2750);
DISPLAY 0.617021 (-2525 2750);
PAINT AQUA (-2525 2750);
FORCEPROP 1 LASTPIN (-2375 2700) $PN 2
J 0
(-2413 2712);
DISPLAY 0.617021 (-2413 2712);
PAINT ORANGE (-2413 2712);
FORCEPROP 1 LAST PART_NUMBER G21796-072
J 0
(-2525 2800);
DISPLAY 0.617021 (-2525 2800);
PAINT BLUE (-2525 2800);
FORCEPROP 1 LAST PACK_TYPE 0402
J 0
(-2225 2550);
DISPLAY 0.617021 (-2225 2550);
PAINT SKYBLUE (-2225 2550);
FORCEPROP 1 LAST WATTAGE 1/16W
J 2
(-2500 2550);
DISPLAY 0.617021 (-2500 2550);
PAINT SKYBLUE (-2500 2550);
FORCEPROP 1 LAST VALUE 4.75K
J 2
(-2500 2600);
DISPLAY 0.617021 (-2500 2600);
PAINT SKYBLUE (-2500 2600);
FORCEPROP 1 LAST TOLERANCE 1%
J 0
(-2475 2600);
DISPLAY 0.617021 (-2475 2600);
PAINT SKYBLUE (-2475 2600);
FORCEPROP 1 LAST MATERIAL CHIP
J 0
(-2475 2550);
DISPLAY 0.617021 (-2475 2550);
PAINT SKYBLUE (-2475 2550);
FORCEPROP 2 LAST BOM_COST SB
J 0
(-2525 2550);
PAINT MONO (-2525 2550);
DISPLAY INVISIBLE (-2525 2550);
FORCEPROP 2 LAST CDS_LIB mstr_discrete
J 0
(-2475 2700);
PAINT ORANGE (-2475 2700);
DISPLAY INVISIBLE (-2475 2700);
FORCEPROP 2 LAST ROOM SB
J 0
(-2475 2700);
PAINT MONO (-2475 2700);
DISPLAY INVISIBLE (-2475 2700);
FORCEPROP 1 LAST PATH I341
J 0
(-2525 2850);
DISPLAY 0.978723 (-2525 2850);
PAINT WHITE (-2525 2850);
DISPLAY INVISIBLE (-2525 2850);
FORCEPROP 2 LAST SEC 1
J 0
(-2525 2900);
DISPLAY 0.680851 (-2525 2900);
PAINT MONO (-2525 2900);
DISPLAY INVISIBLE (-2525 2900);
FORCEPROP 2 LAST SEC_TYPE 0402
J 0
(-2525 2900);
DISPLAY 1.021277 (-2525 2900);
PAINT ORANGE (-2525 2900);
DISPLAY INVISIBLE (-2525 2900);
FORCEADD P3V3_STBY..1
(-2800 2875);
FORCEPROP 3 LASTPIN (-2800 2825) SIG_NAME P3V3_STBY\g
J 0
(-2790 2835);
DISPLAY 0.659574 (-2790 2835);
PAINT MONO (-2790 2835);
DISPLAY INVISIBLE (-2790 2835);
FORCEPROP 1 LAST VOLTAGE 3.3V
J 0
(-2845 2832);
DISPLAY 0.340426 (-2845 2832);
PAINT SKYBLUE (-2845 2832);
DISPLAY INVISIBLE (-2845 2832);
FORCEPROP 2 LAST CDS_LIB mstr_symbols
J 0
(-2800 2875);
PAINT ORANGE (-2800 2875);
DISPLAY INVISIBLE (-2800 2875);
FORCEPROP 1 LAST SIZE 1B
J 0
(-2755 2897);
DISPLAY 0.340426 (-2755 2897);
PAINT GREEN (-2755 2897);
DISPLAY INVISIBLE (-2755 2897);
FORCEPROP 1 LAST PATH I342
J 0
(-2755 2877);
DISPLAY 0.340426 (-2755 2877);
PAINT GREEN (-2755 2877);
DISPLAY INVISIBLE (-2755 2877);
FORCEPROP 1 LAST BODY_TYPE PLUMBING
J 0
(-2845 2832);
DISPLAY 0.340426 (-2845 2832);
PAINT GREEN (-2845 2832);
DISPLAY INVISIBLE (-2845 2832);
FORCEPROP 1 LAST HDL_POWER P3V3_STBY
J 0
(-3100 2750);
DISPLAY 0.872340 (-3100 2750);
PAINT ORANGE (-3100 2750);
DISPLAY INVISIBLE (-3100 2750);
FORCEADD RES..1
(-375 2725);
FORCEPROP 1 LAST VALUE 1.5K
J 2
(-500 2675);
DISPLAY 0.617021 (-500 2675);
PAINT SKYBLUE (-500 2675);
FORCEPROP 1 LAST TOLERANCE 1%
J 0
(-450 2675);
DISPLAY 0.617021 (-450 2675);
PAINT SKYBLUE (-450 2675);
FORCEPROP 1 LAST PART_NUMBER G21796-003
J 0
(-275 2675);
DISPLAY 0.617021 (-275 2675);
PAINT BLUE (-275 2675);
FORCEPROP 1 LAST MATERIAL CHIP
J 0
(-50 2675);
DISPLAY 0.617021 (-50 2675);
PAINT SKYBLUE (-50 2675);
FORCEPROP 1 LAST WATTAGE 1/16W
J 2
(250 2675);
DISPLAY 0.617021 (250 2675);
PAINT SKYBLUE (250 2675);
FORCEPROP 1 LAST PACK_TYPE 0402
J 0
(300 2675);
DISPLAY 0.617021 (300 2675);
PAINT SKYBLUE (300 2675);
FORCEPROP 1 LASTPIN (-275 2725) $PN 2
J 0
(-313 2737);
DISPLAY 0.617021 (-313 2737);
PAINT ORANGE (-313 2737);
FORCEPROP 1 LASTPIN (-475 2725) $PN 1
J 0
(-463 2737);
DISPLAY 0.617021 (-463 2737);
PAINT ORANGE (-463 2737);
FORCEPROP 1 LAST LOCATION R2M8
J 0
(-400 2775);
DISPLAY 0.617021 (-400 2775);
PAINT AQUA (-400 2775);
FORCEPROP 2 LAST BOM_COST SB
J 0
(-425 2575);
PAINT MONO (-425 2575);
DISPLAY INVISIBLE (-425 2575);
FORCEPROP 2 LAST CDS_LIB mstr_discrete
J 0
(-375 2725);
PAINT ORANGE (-375 2725);
DISPLAY INVISIBLE (-375 2725);
FORCEPROP 2 LAST ROOM SB
J 0
(-375 2725);
PAINT MONO (-375 2725);
DISPLAY INVISIBLE (-375 2725);
FORCEPROP 2 LAST SEC 1
J 0
(-425 2925);
DISPLAY 0.680851 (-425 2925);
PAINT MONO (-425 2925);
DISPLAY INVISIBLE (-425 2925);
FORCEPROP 2 LAST SEC_TYPE 0402
J 0
(-425 2925);
DISPLAY 1.021277 (-425 2925);
PAINT ORANGE (-425 2925);
DISPLAY INVISIBLE (-425 2925);
FORCEPROP 1 LAST PATH I349
J 0
(-425 2875);
DISPLAY 0.978723 (-425 2875);
PAINT WHITE (-425 2875);
DISPLAY INVISIBLE (-425 2875);
FORCEADD OFFPAGE..2
(625 2725);
FORCEPROP 2 LAST $XR3 145 
J 0
(814 2689);
DISPLAY 0.638298 (814 2689);
PAINT MONO (814 2689);
FORCEPROP 2 LAST $XR2 120 
J 0
(1024 2725);
DISPLAY 0.638298 (1024 2725);
PAINT MONO (1024 2725);
FORCEPROP 2 LAST $XR1 118 
J 0
(904 2725);
DISPLAY 0.638298 (904 2725);
PAINT MONO (904 2725);
FORCEPROP 2 LAST $XR0 22 
J 0
(814 2725);
DISPLAY 0.638298 (814 2725);
PAINT MONO (814 2725);
FORCEPROP 2 LAST CDS_LIB mstr_standard
J 0
(625 2725);
PAINT ORANGE (625 2725);
DISPLAY INVISIBLE (625 2725);
FORCEPROP 2 LAST PATH I350
J 0
(925 2775);
DISPLAY 1.021277 (925 2775);
PAINT ORANGE (925 2775);
DISPLAY INVISIBLE (925 2775);
FORCEPROP 2 LAST BOM_COST SB
J 0
(825 2775);
PAINT MONO (825 2775);
DISPLAY INVISIBLE (825 2775);
FORCEPROP 1 LAST OFFPAGE TRUE
J 0
(950 2600);
PAINT GREEN (950 2600);
DISPLAY INVISIBLE (950 2600);
FORCEPROP 1 LAST COMMENT_BODY TRUE
J 0
(580 2630);
DISPLAY 1.170213 (580 2630);
PAINT GREEN (580 2630);
DISPLAY INVISIBLE (580 2630);
FORCEADD OFFPAGE..2
(625 2475);
FORCEPROP 2 LAST $XR2 145 
J 0
(1024 2475);
DISPLAY 0.638298 (1024 2475);
PAINT MONO (1024 2475);
FORCEPROP 2 LAST $XR1 120 
J 0
(904 2475);
DISPLAY 0.638298 (904 2475);
PAINT MONO (904 2475);
FORCEPROP 2 LAST $XR0 56 
J 0
(814 2475);
DISPLAY 0.638298 (814 2475);
PAINT MONO (814 2475);
FORCEPROP 2 LAST CDS_LIB mstr_standard
J 0
(625 2475);
PAINT ORANGE (625 2475);
DISPLAY INVISIBLE (625 2475);
FORCEPROP 2 LAST PATH I351
J 0
(925 2525);
DISPLAY 1.021277 (925 2525);
PAINT ORANGE (925 2525);
DISPLAY INVISIBLE (925 2525);
FORCEPROP 2 LAST BOM_COST SB
J 0
(825 2525);
PAINT MONO (825 2525);
DISPLAY INVISIBLE (825 2525);
FORCEPROP 1 LAST OFFPAGE TRUE
J 0
(950 2350);
PAINT GREEN (950 2350);
DISPLAY INVISIBLE (950 2350);
FORCEPROP 1 LAST COMMENT_BODY TRUE
J 0
(580 2380);
DISPLAY 1.170213 (580 2380);
PAINT GREEN (580 2380);
DISPLAY INVISIBLE (580 2380);
FORCEADD RES..1
(-375 2475);
FORCEPROP 1 LAST TOLERANCE 1%
J 0
(-475 2425);
DISPLAY 0.617021 (-475 2425);
PAINT SKYBLUE (-475 2425);
FORCEPROP 1 LASTPIN (-475 2475) $PN 1
J 0
(-463 2487);
DISPLAY 0.617021 (-463 2487);
PAINT ORANGE (-463 2487);
FORCEPROP 1 LAST LOCATION R2N29
J 0
(-425 2525);
DISPLAY 0.617021 (-425 2525);
PAINT AQUA (-425 2525);
FORCEPROP 1 LASTPIN (-275 2475) $PN 2
J 0
(-313 2487);
DISPLAY 0.617021 (-313 2487);
PAINT ORANGE (-313 2487);
FORCEPROP 1 LAST PART_NUMBER G21796-003
J 0
(-250 2425);
DISPLAY 0.617021 (-250 2425);
PAINT BLUE (-250 2425);
FORCEPROP 1 LAST MATERIAL CHIP
J 0
(0 2425);
DISPLAY 0.617021 (0 2425);
PAINT SKYBLUE (0 2425);
FORCEPROP 1 LAST PACK_TYPE 0402
J 0
(300 2425);
DISPLAY 0.617021 (300 2425);
PAINT SKYBLUE (300 2425);
FORCEPROP 1 LAST VALUE 1.5K
J 2
(-500 2425);
DISPLAY 0.617021 (-500 2425);
PAINT SKYBLUE (-500 2425);
FORCEPROP 1 LAST WATTAGE 1/16W
J 2
(275 2425);
DISPLAY 0.617021 (275 2425);
PAINT SKYBLUE (275 2425);
FORCEPROP 2 LAST BOM_COST SB
J 0
(-425 2325);
PAINT MONO (-425 2325);
DISPLAY INVISIBLE (-425 2325);
FORCEPROP 2 LAST CDS_LIB mstr_discrete
J 0
(-375 2475);
PAINT ORANGE (-375 2475);
DISPLAY INVISIBLE (-375 2475);
FORCEPROP 2 LAST ROOM SB
J 0
(-375 2475);
PAINT MONO (-375 2475);
DISPLAY INVISIBLE (-375 2475);
FORCEPROP 2 LAST SEC 1
J 0
(-425 2675);
DISPLAY 0.680851 (-425 2675);
PAINT MONO (-425 2675);
DISPLAY INVISIBLE (-425 2675);
FORCEPROP 2 LAST SEC_TYPE 0402
J 0
(-425 2675);
DISPLAY 1.021277 (-425 2675);
PAINT ORANGE (-425 2675);
DISPLAY INVISIBLE (-425 2675);
FORCEPROP 1 LAST PATH I352
J 0
(-425 2625);
DISPLAY 0.978723 (-425 2625);
PAINT WHITE (-425 2625);
DISPLAY INVISIBLE (-425 2625);
FORCEADD P3V3_STBY..1
(-625 2950);
FORCEPROP 3 LASTPIN (-625 2900) SIG_NAME P3V3_STBY\g
J 0
(-615 2910);
DISPLAY 0.659574 (-615 2910);
PAINT MONO (-615 2910);
DISPLAY INVISIBLE (-615 2910);
FORCEPROP 1 LAST PATH I353
J 0
(-580 2952);
DISPLAY 0.340426 (-580 2952);
PAINT GREEN (-580 2952);
DISPLAY INVISIBLE (-580 2952);
FORCEPROP 2 LAST CDS_LIB mstr_symbols
J 0
(-625 2950);
PAINT ORANGE (-625 2950);
DISPLAY INVISIBLE (-625 2950);
FORCEPROP 1 LAST SIZE 1B
J 0
(-580 2972);
DISPLAY 0.340426 (-580 2972);
PAINT GREEN (-580 2972);
DISPLAY INVISIBLE (-580 2972);
FORCEPROP 1 LAST VOLTAGE 3.3V
J 0
(-670 2907);
DISPLAY 0.340426 (-670 2907);
PAINT SKYBLUE (-670 2907);
DISPLAY INVISIBLE (-670 2907);
FORCEPROP 1 LAST BODY_TYPE PLUMBING
J 0
(-670 2907);
DISPLAY 0.340426 (-670 2907);
PAINT GREEN (-670 2907);
DISPLAY INVISIBLE (-670 2907);
FORCEPROP 1 LAST HDL_POWER P3V3_STBY
J 0
(-925 2825);
DISPLAY 0.872340 (-925 2825);
PAINT ORANGE (-925 2825);
DISPLAY INVISIBLE (-925 2825);
FORCEADD OFFPAGE..2
(-3850 3475);
FORCEPROP 2 LAST $XR2 146 
J 0
(-3421 3475);
DISPLAY 0.638298 (-3421 3475);
PAINT MONO (-3421 3475);
FORCEPROP 2 LAST $XR1 119 
J 0
(-3541 3475);
DISPLAY 0.638298 (-3541 3475);
PAINT MONO (-3541 3475);
FORCEPROP 2 LAST $XR0 249 
J 0
(-3661 3475);
DISPLAY 0.638298 (-3661 3475);
PAINT MONO (-3661 3475);
FORCEPROP 2 LAST CDS_LIB mstr_standard
J 0
(-3850 3475);
PAINT MONO (-3850 3475);
DISPLAY INVISIBLE (-3850 3475);
FORCEPROP 2 LAST PATH I354
J 0
(-3525 3525);
DISPLAY 1.021277 (-3525 3525);
PAINT ORANGE (-3525 3525);
DISPLAY INVISIBLE (-3525 3525);
FORCEPROP 1 LAST OFFPAGE TRUE
J 0
(-3525 3350);
DISPLAY 0.872340 (-3525 3350);
PAINT GREEN (-3525 3350);
DISPLAY INVISIBLE (-3525 3350);
FORCEPROP 1 LAST COMMENT_BODY TRUE
J 0
(-3895 3380);
DISPLAY 0.872340 (-3895 3380);
PAINT GREEN (-3895 3380);
DISPLAY INVISIBLE (-3895 3380);
FORCEADD RES..1
(-375 3725);
FORCEPROP 1 LAST VALUE 4.75K
J 2
(-475 3725);
DISPLAY 0.617021 (-475 3725);
PAINT SKYBLUE (-475 3725);
FORCEPROP 1 LASTPIN (-275 3725) $PN 2
J 0
(-313 3737);
DISPLAY 0.617021 (-313 3737);
PAINT ORANGE (-313 3737);
FORCEPROP 1 LAST MATERIAL CHIP
J 0
(-150 3675);
DISPLAY 0.617021 (-150 3675);
PAINT SKYBLUE (-150 3675);
FORCEPROP 1 LAST TOLERANCE 1%
J 0
(-225 3675);
DISPLAY 0.617021 (-225 3675);
PAINT SKYBLUE (-225 3675);
FORCEPROP 1 LAST WATTAGE 1/16W
J 2
(-475 3675);
DISPLAY 0.617021 (-475 3675);
PAINT SKYBLUE (-475 3675);
FORCEPROP 1 LAST PART_NUMBER G21796-072
J 0
(-450 3675);
DISPLAY 0.617021 (-450 3675);
PAINT BLUE (-450 3675);
FORCEPROP 1 LAST PACK_TYPE 0402
J 0
(-250 3725);
DISPLAY 0.617021 (-250 3725);
PAINT SKYBLUE (-250 3725);
FORCEPROP 1 LAST LOCATION R7D44
J 0
(-425 3775);
DISPLAY 0.617021 (-425 3775);
PAINT AQUA (-425 3775);
FORCEPROP 1 LASTPIN (-475 3725) $PN 1
J 0
(-463 3737);
DISPLAY 0.617021 (-463 3737);
PAINT ORANGE (-463 3737);
FORCEPROP 2 LAST ROOM SB_PU_PD
J 0
(-425 3825);
DISPLAY 1.021277 (-425 3825);
PAINT ORANGE (-425 3825);
DISPLAY INVISIBLE (-425 3825);
FORCEPROP 1 LAST PATH I356
J 0
(-425 3875);
DISPLAY 0.978723 (-425 3875);
PAINT WHITE (-425 3875);
DISPLAY INVISIBLE (-425 3875);
FORCEPROP 2 LAST SEC_TYPE 0402
J 0
(-425 3925);
DISPLAY 1.021277 (-425 3925);
PAINT ORANGE (-425 3925);
DISPLAY INVISIBLE (-425 3925);
FORCEPROP 2 LAST SEC 1
J 0
(-425 3925);
DISPLAY 0.680851 (-425 3925);
PAINT MONO (-425 3925);
DISPLAY INVISIBLE (-425 3925);
FORCEPROP 2 LAST CDS_LIB mstr_discrete
J 0
(-375 3725);
PAINT ORANGE (-375 3725);
DISPLAY INVISIBLE (-375 3725);
FORCEADD OFFPAGE..2
(775 3725);
FORCEPROP 2 LAST $XR1 121 
J 0
(1084 3725);
DISPLAY 0.638298 (1084 3725);
PAINT MONO (1084 3725);
FORCEPROP 2 LAST $XR0 250 
J 0
(964 3725);
DISPLAY 0.638298 (964 3725);
PAINT MONO (964 3725);
FORCEPROP 2 LAST BOM_COST SB
J 0
(975 3775);
PAINT MONO (975 3775);
DISPLAY INVISIBLE (975 3775);
FORCEPROP 2 LAST PATH I358
J 0
(950 3800);
DISPLAY 1.021277 (950 3800);
PAINT ORANGE (950 3800);
DISPLAY INVISIBLE (950 3800);
FORCEPROP 2 LAST CDS_LIB mstr_standard
J 0
(775 3725);
PAINT ORANGE (775 3725);
DISPLAY INVISIBLE (775 3725);
FORCEPROP 1 LAST OFFPAGE TRUE
J 0
(1100 3600);
PAINT GREEN (1100 3600);
DISPLAY INVISIBLE (1100 3600);
FORCEPROP 1 LAST COMMENT_BODY TRUE
J 0
(730 3630);
DISPLAY 1.170213 (730 3630);
PAINT GREEN (730 3630);
DISPLAY INVISIBLE (730 3630);
FORCEADD OFFPAGE..2
(775 3525);
FORCEPROP 2 LAST $XR1 121 
J 0
(1084 3525);
DISPLAY 0.638298 (1084 3525);
PAINT MONO (1084 3525);
FORCEPROP 2 LAST $XR0 250 
J 0
(964 3525);
DISPLAY 0.638298 (964 3525);
PAINT MONO (964 3525);
FORCEPROP 2 LAST PATH I359
J 0
(950 3600);
DISPLAY 1.021277 (950 3600);
PAINT ORANGE (950 3600);
DISPLAY INVISIBLE (950 3600);
FORCEPROP 2 LAST BOM_COST SB
J 0
(975 3575);
PAINT MONO (975 3575);
DISPLAY INVISIBLE (975 3575);
FORCEPROP 2 LAST CDS_LIB mstr_standard
J 0
(775 3525);
PAINT ORANGE (775 3525);
DISPLAY INVISIBLE (775 3525);
FORCEPROP 1 LAST OFFPAGE TRUE
J 0
(1100 3400);
PAINT GREEN (1100 3400);
DISPLAY INVISIBLE (1100 3400);
FORCEPROP 1 LAST COMMENT_BODY TRUE
J 0
(730 3430);
DISPLAY 1.170213 (730 3430);
PAINT GREEN (730 3430);
DISPLAY INVISIBLE (730 3430);
FORCEADD RES..1
(-4800 1500);
FORCEPROP 1 LAST WATTAGE 1/16W
J 2
(-4870 1410);
DISPLAY 0.617021 (-4870 1410);
PAINT SKYBLUE (-4870 1410);
FORCEPROP 1 LAST VALUE 10.0K
J 2
(-4825 1450);
DISPLAY 0.617021 (-4825 1450);
PAINT SKYBLUE (-4825 1450);
FORCEPROP 1 LAST PART_NUMBER G21796-016
J 0
(-4725 1550);
DISPLAY 0.617021 (-4725 1550);
PAINT BLUE (-4725 1550);
FORCEPROP 1 LAST LOCATION R2P22
J 0
(-4950 1550);
DISPLAY 0.617021 (-4950 1550);
PAINT AQUA (-4950 1550);
FORCEPROP 1 LASTPIN (-4900 1500) $PN 1
J 0
(-4888 1512);
DISPLAY 0.617021 (-4888 1512);
PAINT ORANGE (-4888 1512);
FORCEPROP 1 LASTPIN (-4700 1500) $PN 2
J 0
(-4738 1512);
DISPLAY 0.617021 (-4738 1512);
PAINT ORANGE (-4738 1512);
FORCEPROP 1 LAST PACK_TYPE 0402
J 0
(-4690 1460);
DISPLAY 0.617021 (-4690 1460);
PAINT SKYBLUE (-4690 1460);
FORCEPROP 1 LAST TOLERANCE 1%
J 0
(-4770 1450);
DISPLAY 0.617021 (-4770 1450);
PAINT SKYBLUE (-4770 1450);
FORCEPROP 1 LAST MATERIAL CHIP
J 0
(-4860 1410);
DISPLAY 0.617021 (-4860 1410);
PAINT SKYBLUE (-4860 1410);
FORCEPROP 2 LAST BOM_COST SB
J 0
(-4850 1350);
PAINT MONO (-4850 1350);
DISPLAY INVISIBLE (-4850 1350);
FORCEPROP 2 LAST ROOM SB
J 0
(-4800 1500);
PAINT MONO (-4800 1500);
DISPLAY INVISIBLE (-4800 1500);
FORCEPROP 2 LAST CDS_LIB mstr_discrete
J 0
(-4800 1500);
PAINT ORANGE (-4800 1500);
DISPLAY INVISIBLE (-4800 1500);
FORCEPROP 1 LAST PATH I360
J 0
(-4850 1650);
DISPLAY 0.978723 (-4850 1650);
PAINT WHITE (-4850 1650);
DISPLAY INVISIBLE (-4850 1650);
FORCEPROP 2 LAST SEC 1
J 0
(-4850 1700);
DISPLAY 0.680851 (-4850 1700);
PAINT MONO (-4850 1700);
DISPLAY INVISIBLE (-4850 1700);
FORCEPROP 2 LAST SEC_TYPE 0402
J 0
(-4850 1700);
DISPLAY 1.021277 (-4850 1700);
PAINT ORANGE (-4850 1700);
DISPLAY INVISIBLE (-4850 1700);
FORCEADD OFFPAGE..2
(-3925 1500);
FORCEPROP 2 LAST $XR1 190 
J 0
(-3616 1500);
DISPLAY 0.638298 (-3616 1500);
PAINT MONO (-3616 1500);
FORCEPROP 2 LAST $XR0 119 
J 0
(-3736 1500);
DISPLAY 0.638298 (-3736 1500);
PAINT MONO (-3736 1500);
FORCEPROP 2 LAST CDS_LIB mstr_standard
J 0
(-3925 1500);
PAINT ORANGE (-3925 1500);
DISPLAY INVISIBLE (-3925 1500);
FORCEPROP 2 LAST BOM_COST SB
J 0
(-3725 1550);
PAINT MONO (-3725 1550);
DISPLAY INVISIBLE (-3725 1550);
FORCEPROP 2 LAST PATH I361
J 0
(-3750 1575);
DISPLAY 1.021277 (-3750 1575);
PAINT ORANGE (-3750 1575);
DISPLAY INVISIBLE (-3750 1575);
FORCEPROP 1 LAST OFFPAGE TRUE
J 0
(-3600 1375);
PAINT GREEN (-3600 1375);
DISPLAY INVISIBLE (-3600 1375);
FORCEPROP 1 LAST COMMENT_BODY TRUE
J 0
(-3970 1405);
DISPLAY 1.170213 (-3970 1405);
PAINT GREEN (-3970 1405);
DISPLAY INVISIBLE (-3970 1405);
FORCEADD RES..1
(-2475 2450);
FORCEPROP 1 LASTPIN (-2575 2450) $PN 1
J 0
(-2563 2462);
DISPLAY 0.617021 (-2563 2462);
PAINT ORANGE (-2563 2462);
FORCEPROP 1 LASTPIN (-2375 2450) $PN 2
J 0
(-2413 2462);
DISPLAY 0.617021 (-2413 2462);
PAINT ORANGE (-2413 2462);
FORCEPROP 1 LAST LOCATION R8D44
J 0
(-2525 2500);
DISPLAY 0.617021 (-2525 2500);
PAINT AQUA (-2525 2500);
FORCEPROP 1 LAST PART_NUMBER G21796-016
J 0
(-2350 2500);
DISPLAY 0.617021 (-2350 2500);
PAINT BLUE (-2350 2500);
FORCEPROP 1 LAST TOLERANCE 1%
J 0
(-2445 2400);
DISPLAY 0.617021 (-2445 2400);
PAINT SKYBLUE (-2445 2400);
FORCEPROP 1 LAST WATTAGE 1/16W
J 2
(-2545 2360);
DISPLAY 0.617021 (-2545 2360);
PAINT SKYBLUE (-2545 2360);
FORCEPROP 1 LAST VALUE 10.0K
J 2
(-2500 2400);
DISPLAY 0.617021 (-2500 2400);
PAINT SKYBLUE (-2500 2400);
FORCEPROP 1 LAST MATERIAL CHIP
J 0
(-2535 2360);
DISPLAY 0.617021 (-2535 2360);
PAINT SKYBLUE (-2535 2360);
FORCEPROP 1 LAST PACK_TYPE 0402
J 0
(-2365 2410);
DISPLAY 0.617021 (-2365 2410);
PAINT SKYBLUE (-2365 2410);
FORCEPROP 2 LAST BOM_COST SB
J 0
(-2525 2300);
PAINT MONO (-2525 2300);
DISPLAY INVISIBLE (-2525 2300);
FORCEPROP 2 LAST CDS_LIB mstr_discrete
J 0
(-2475 2450);
PAINT ORANGE (-2475 2450);
DISPLAY INVISIBLE (-2475 2450);
FORCEPROP 2 LAST ROOM SB
J 0
(-2475 2450);
PAINT MONO (-2475 2450);
DISPLAY INVISIBLE (-2475 2450);
FORCEPROP 1 LAST PATH I362
J 0
(-2525 2600);
DISPLAY 0.978723 (-2525 2600);
PAINT WHITE (-2525 2600);
DISPLAY INVISIBLE (-2525 2600);
FORCEPROP 2 LAST SEC 1
J 0
(-2525 2650);
DISPLAY 0.680851 (-2525 2650);
PAINT MONO (-2525 2650);
DISPLAY INVISIBLE (-2525 2650);
FORCEPROP 2 LAST SEC_TYPE 0402
J 0
(-2525 2650);
DISPLAY 1.021277 (-2525 2650);
PAINT ORANGE (-2525 2650);
DISPLAY INVISIBLE (-2525 2650);
FORCEADD OFFPAGE..2
(-1575 2450);
FORCEPROP 2 LAST $XR1 190 
J 0
(-1266 2450);
DISPLAY 0.638298 (-1266 2450);
PAINT MONO (-1266 2450);
FORCEPROP 2 LAST $XR0 120 
J 0
(-1386 2450);
DISPLAY 0.638298 (-1386 2450);
PAINT MONO (-1386 2450);
FORCEPROP 2 LAST CDS_LIB mstr_standard
J 0
(-1575 2450);
PAINT ORANGE (-1575 2450);
DISPLAY INVISIBLE (-1575 2450);
FORCEPROP 2 LAST BOM_COST SB
J 0
(-1375 2500);
PAINT MONO (-1375 2500);
DISPLAY INVISIBLE (-1375 2500);
FORCEPROP 2 LAST PATH I363
J 0
(-1400 2525);
DISPLAY 1.021277 (-1400 2525);
PAINT ORANGE (-1400 2525);
DISPLAY INVISIBLE (-1400 2525);
FORCEPROP 1 LAST OFFPAGE TRUE
J 0
(-1250 2325);
PAINT GREEN (-1250 2325);
DISPLAY INVISIBLE (-1250 2325);
FORCEPROP 1 LAST COMMENT_BODY TRUE
J 0
(-1620 2355);
DISPLAY 1.170213 (-1620 2355);
PAINT GREEN (-1620 2355);
DISPLAY INVISIBLE (-1620 2355);
FORCEADD RES..1
(-375 3525);
FORCEPROP 1 LAST TOLERANCE 1%
J 0
(-225 3475);
DISPLAY 0.617021 (-225 3475);
PAINT SKYBLUE (-225 3475);
FORCEPROP 1 LAST MATERIAL CHIP
J 0
(-150 3475);
DISPLAY 0.617021 (-150 3475);
PAINT SKYBLUE (-150 3475);
FORCEPROP 1 LAST PART_NUMBER G21796-072
J 0
(-450 3475);
DISPLAY 0.617021 (-450 3475);
PAINT BLUE (-450 3475);
FORCEPROP 1 LAST PACK_TYPE 0402
J 0
(-250 3525);
DISPLAY 0.617021 (-250 3525);
PAINT SKYBLUE (-250 3525);
FORCEPROP 1 LAST WATTAGE 1/16W
J 2
(-475 3475);
DISPLAY 0.617021 (-475 3475);
PAINT SKYBLUE (-475 3475);
FORCEPROP 1 LAST VALUE 4.75K
J 2
(-475 3525);
DISPLAY 0.617021 (-475 3525);
PAINT SKYBLUE (-475 3525);
FORCEPROP 1 LAST LOCATION R3P53
J 0
(-425 3575);
DISPLAY 0.617021 (-425 3575);
PAINT AQUA (-425 3575);
FORCEPROP 1 LASTPIN (-275 3525) $PN 2
J 0
(-313 3537);
DISPLAY 0.787234 (-313 3537);
PAINT ORANGE (-313 3537);
DISPLAY INVISIBLE (-313 3537);
FORCEPROP 1 LASTPIN (-475 3525) $PN 1
J 0
(-463 3537);
DISPLAY 0.787234 (-463 3537);
PAINT ORANGE (-463 3537);
DISPLAY INVISIBLE (-463 3537);
FORCEPROP 2 LAST CDS_LIB mstr_discrete
J 0
(-375 3525);
PAINT MONO (-375 3525);
DISPLAY INVISIBLE (-375 3525);
FORCEPROP 1 LAST PATH I365
J 0
(-425 3675);
DISPLAY 0.978723 (-425 3675);
PAINT WHITE (-425 3675);
DISPLAY INVISIBLE (-425 3675);
FORCEPROP 2 LAST ROOM SB_PU_PD
J 0
(-425 3625);
DISPLAY 1.021277 (-425 3625);
PAINT ORANGE (-425 3625);
DISPLAY INVISIBLE (-425 3625);
FORCEADD RES..2
R 3
(-400 4875);
FORCEPROP 1 LAST PART_NUMBER G21796-026
J 0
(-225 4885);
DISPLAY 0.617021 (-225 4885);
PAINT BLUE (-225 4885);
FORCEPROP 1 LAST MATERIAL EMPTY
J 0
(-125 4810);
DISPLAY 0.617021 (-125 4810);
PAINT RED (-125 4810);
FORCEPROP 1 LAST WATTAGE 1/16W
J 0
(75 4810);
DISPLAY 0.617021 (75 4810);
PAINT SKYBLUE (75 4810);
FORCEPROP 1 LAST VALUE 1.00K
J 0
(-525 4805);
DISPLAY 0.617021 (-525 4805);
PAINT SKYBLUE (-525 4805);
FORCEPROP 1 LAST PACK_TYPE 0402
J 0
(-275 4810);
DISPLAY 0.617021 (-275 4810);
PAINT SKYBLUE (-275 4810);
FORCEPROP 1 LASTPIN (-500 4875) $PN 1
J 2
(-487 4895);
DISPLAY 0.617021 (-487 4895);
PAINT ORANGE (-487 4895);
FORCEPROP 1 LAST TOLERANCE 1%
J 0
(-375 4805);
DISPLAY 0.617021 (-375 4805);
PAINT SKYBLUE (-375 4805);
FORCEPROP 1 LASTPIN (-300 4875) $PN 2
J 2
(-260 4895);
DISPLAY 0.617021 (-260 4895);
PAINT ORANGE (-260 4895);
FORCEPROP 1 LAST LOCATION R3P5
J 0
(-600 4955);
DISPLAY 0.617021 (-600 4955);
PAINT AQUA (-600 4955);
FORCEPROP 1 LAST PATH I366
R 1
J 0
(-575 4825);
DISPLAY 0.978723 (-575 4825);
PAINT WHITE (-575 4825);
DISPLAY INVISIBLE (-575 4825);
FORCEPROP 2 LAST CDS_LOCATION R3P5
R 1
J 2
(-375 5055);
DISPLAY 0.617021 (-375 5055);
PAINT AQUA (-375 5055);
DISPLAY INVISIBLE (-375 5055);
FORCEPROP 0 LAST CDS_SEC 1
R 1
J 0
(-500 5125);
PAINT MONO (-500 5125);
DISPLAY INVISIBLE (-500 5125);
FORCEPROP 2 LAST CDS_LIB mstr_discrete
R 1
J 0
(-400 4875);
PAINT ORANGE (-400 4875);
DISPLAY INVISIBLE (-400 4875);
FORCEPROP 0 LAST ROOM DEBUG
R 1
J 2
(-525 4850);
DISPLAY 1.021277 (-525 4850);
PAINT ORANGE (-525 4850);
DISPLAY INVISIBLE (-525 4850);
FORCEPROP 2 LAST SEC 1
R 1
J 0
(-625 4825);
DISPLAY 0.680851 (-625 4825);
PAINT MONO (-625 4825);
DISPLAY INVISIBLE (-625 4825);
FORCEPROP 2 LAST SEC_TYPE 0402
R 1
J 0
(-625 4825);
DISPLAY 1.021277 (-625 4825);
PAINT ORANGE (-625 4825);
DISPLAY INVISIBLE (-625 4825);
FORCEADD RES..2
R 3
(-375 4650);
FORCEPROP 1 LAST TOLERANCE 1%
J 0
(-350 4580);
DISPLAY 0.617021 (-350 4580);
PAINT SKYBLUE (-350 4580);
FORCEPROP 1 LAST WATTAGE 1/16W
J 0
(100 4585);
DISPLAY 0.617021 (100 4585);
PAINT SKYBLUE (100 4585);
FORCEPROP 1 LASTPIN (-475 4650) $PN 1
J 2
(-462 4670);
DISPLAY 0.617021 (-462 4670);
PAINT ORANGE (-462 4670);
FORCEPROP 1 LAST PART_NUMBER G21796-026
J 0
(-200 4660);
DISPLAY 0.617021 (-200 4660);
PAINT BLUE (-200 4660);
FORCEPROP 1 LAST VALUE 1.00K
J 0
(-500 4580);
DISPLAY 0.617021 (-500 4580);
PAINT SKYBLUE (-500 4580);
FORCEPROP 1 LASTPIN (-275 4650) $PN 2
J 2
(-235 4670);
DISPLAY 0.617021 (-235 4670);
PAINT ORANGE (-235 4670);
FORCEPROP 1 LAST MATERIAL EMPTY
J 0
(-100 4585);
DISPLAY 0.617021 (-100 4585);
PAINT RED (-100 4585);
FORCEPROP 1 LAST PACK_TYPE 0402
J 0
(-250 4585);
DISPLAY 0.617021 (-250 4585);
PAINT SKYBLUE (-250 4585);
FORCEPROP 1 LAST LOCATION R3P6
J 0
(-600 4705);
DISPLAY 0.617021 (-600 4705);
PAINT AQUA (-600 4705);
FORCEPROP 1 LAST PATH I367
R 1
J 2
(-550 4600);
DISPLAY 0.978723 (-550 4600);
PAINT WHITE (-550 4600);
DISPLAY INVISIBLE (-550 4600);
FORCEPROP 2 LAST SEC_TYPE 0402
R 1
J 0
(-600 4600);
DISPLAY 1.021277 (-600 4600);
PAINT ORANGE (-600 4600);
DISPLAY INVISIBLE (-600 4600);
FORCEPROP 2 LAST SEC 1
R 1
J 0
(-600 4600);
DISPLAY 0.680851 (-600 4600);
PAINT MONO (-600 4600);
DISPLAY INVISIBLE (-600 4600);
FORCEPROP 0 LAST ROOM DEBUG
R 1
J 2
(-500 4625);
DISPLAY 1.021277 (-500 4625);
PAINT ORANGE (-500 4625);
DISPLAY INVISIBLE (-500 4625);
FORCEPROP 2 LAST CDS_LIB mstr_discrete
R 1
J 0
(-375 4650);
PAINT ORANGE (-375 4650);
DISPLAY INVISIBLE (-375 4650);
FORCEPROP 0 LAST CDS_SEC 1
R 1
J 0
(-475 4900);
PAINT MONO (-475 4900);
DISPLAY INVISIBLE (-475 4900);
FORCEPROP 2 LAST CDS_LOCATION R3P6
R 1
J 2
(-350 4830);
DISPLAY 0.617021 (-350 4830);
PAINT AQUA (-350 4830);
DISPLAY INVISIBLE (-350 4830);
FORCEADD RES..2
R 3
(-375 4400);
FORCEPROP 1 LAST TOLERANCE 1%
J 0
(-350 4330);
DISPLAY 0.617021 (-350 4330);
PAINT SKYBLUE (-350 4330);
FORCEPROP 1 LASTPIN (-475 4400) $PN 1
J 2
(-462 4420);
DISPLAY 0.617021 (-462 4420);
PAINT ORANGE (-462 4420);
FORCEPROP 1 LAST VALUE 1.00K
J 0
(-500 4330);
DISPLAY 0.617021 (-500 4330);
PAINT SKYBLUE (-500 4330);
FORCEPROP 1 LAST LOCATION R3N15
J 0
(-600 4455);
DISPLAY 0.617021 (-600 4455);
PAINT AQUA (-600 4455);
FORCEPROP 1 LAST WATTAGE 1/16W
J 0
(100 4335);
DISPLAY 0.617021 (100 4335);
PAINT SKYBLUE (100 4335);
FORCEPROP 1 LAST MATERIAL EMPTY
J 0
(-100 4335);
DISPLAY 0.617021 (-100 4335);
PAINT RED (-100 4335);
FORCEPROP 1 LAST PACK_TYPE 0402
J 0
(-250 4335);
DISPLAY 0.617021 (-250 4335);
PAINT SKYBLUE (-250 4335);
FORCEPROP 1 LAST PART_NUMBER G21796-026
J 0
(-200 4410);
DISPLAY 0.617021 (-200 4410);
PAINT BLUE (-200 4410);
FORCEPROP 1 LASTPIN (-275 4400) $PN 2
J 2
(-235 4420);
DISPLAY 0.617021 (-235 4420);
PAINT ORANGE (-235 4420);
FORCEPROP 2 LAST SEC_TYPE 0402
R 1
J 0
(-600 4350);
DISPLAY 1.021277 (-600 4350);
PAINT ORANGE (-600 4350);
DISPLAY INVISIBLE (-600 4350);
FORCEPROP 2 LAST SEC 1
R 1
J 0
(-600 4350);
DISPLAY 0.680851 (-600 4350);
PAINT MONO (-600 4350);
DISPLAY INVISIBLE (-600 4350);
FORCEPROP 0 LAST ROOM DEBUG
R 1
J 2
(-500 4375);
DISPLAY 1.021277 (-500 4375);
PAINT ORANGE (-500 4375);
DISPLAY INVISIBLE (-500 4375);
FORCEPROP 2 LAST CDS_LIB mstr_discrete
R 1
J 0
(-375 4400);
PAINT ORANGE (-375 4400);
DISPLAY INVISIBLE (-375 4400);
FORCEPROP 0 LAST CDS_SEC 1
R 1
J 0
(-475 4650);
PAINT MONO (-475 4650);
DISPLAY INVISIBLE (-475 4650);
FORCEPROP 1 LAST PATH I368
R 1
J 2
(-550 4350);
DISPLAY 0.978723 (-550 4350);
PAINT WHITE (-550 4350);
DISPLAY INVISIBLE (-550 4350);
FORCEPROP 2 LAST CDS_LOCATION R3N15
R 1
J 2
(-350 4580);
DISPLAY 0.617021 (-350 4580);
PAINT AQUA (-350 4580);
DISPLAY INVISIBLE (-350 4580);
FORCEADD RES..2
R 3
(-375 4175);
FORCEPROP 1 LAST TOLERANCE 1%
J 0
(-350 4105);
DISPLAY 0.617021 (-350 4105);
PAINT SKYBLUE (-350 4105);
FORCEPROP 1 LAST MATERIAL EMPTY
J 0
(-100 4110);
DISPLAY 0.617021 (-100 4110);
PAINT RED (-100 4110);
FORCEPROP 1 LAST WATTAGE 1/16W
J 0
(100 4110);
DISPLAY 0.617021 (100 4110);
PAINT SKYBLUE (100 4110);
FORCEPROP 1 LASTPIN (-275 4175) $PN 2
J 2
(-235 4195);
DISPLAY 0.617021 (-235 4195);
PAINT ORANGE (-235 4195);
FORCEPROP 1 LASTPIN (-475 4175) $PN 1
J 2
(-462 4195);
DISPLAY 0.617021 (-462 4195);
PAINT ORANGE (-462 4195);
FORCEPROP 1 LAST VALUE 1.00K
J 0
(-500 4105);
DISPLAY 0.617021 (-500 4105);
PAINT SKYBLUE (-500 4105);
FORCEPROP 1 LAST PACK_TYPE 0402
J 0
(-250 4110);
DISPLAY 0.617021 (-250 4110);
PAINT SKYBLUE (-250 4110);
FORCEPROP 1 LAST PART_NUMBER G21796-026
J 0
(-200 4185);
DISPLAY 0.617021 (-200 4185);
PAINT BLUE (-200 4185);
FORCEPROP 1 LAST LOCATION R3N16
J 0
(-600 4230);
DISPLAY 0.617021 (-600 4230);
PAINT AQUA (-600 4230);
FORCEPROP 2 LAST SEC_TYPE 0402
R 1
J 0
(-600 4125);
DISPLAY 1.021277 (-600 4125);
PAINT ORANGE (-600 4125);
DISPLAY INVISIBLE (-600 4125);
FORCEPROP 2 LAST SEC 1
R 1
J 0
(-600 4125);
DISPLAY 0.680851 (-600 4125);
PAINT MONO (-600 4125);
DISPLAY INVISIBLE (-600 4125);
FORCEPROP 0 LAST ROOM DEBUG
R 1
J 2
(-500 4150);
DISPLAY 1.021277 (-500 4150);
PAINT ORANGE (-500 4150);
DISPLAY INVISIBLE (-500 4150);
FORCEPROP 2 LAST CDS_LIB mstr_discrete
R 1
J 0
(-375 4175);
PAINT ORANGE (-375 4175);
DISPLAY INVISIBLE (-375 4175);
FORCEPROP 0 LAST CDS_SEC 1
R 1
J 0
(-475 4425);
PAINT MONO (-475 4425);
DISPLAY INVISIBLE (-475 4425);
FORCEPROP 1 LAST PATH I369
R 1
J 2
(-550 4125);
DISPLAY 0.978723 (-550 4125);
PAINT WHITE (-550 4125);
DISPLAY INVISIBLE (-550 4125);
FORCEPROP 2 LAST CDS_LOCATION R3N16
R 1
J 2
(-350 4355);
DISPLAY 0.617021 (-350 4355);
PAINT AQUA (-350 4355);
DISPLAY INVISIBLE (-350 4355);
FORCEADD RES..2
R 3
(-400 5100);
FORCEPROP 1 LAST MATERIAL EMPTY
J 0
(-125 5035);
DISPLAY 0.617021 (-125 5035);
PAINT RED (-125 5035);
FORCEPROP 1 LAST WATTAGE 1/16W
J 0
(75 5035);
DISPLAY 0.617021 (75 5035);
PAINT SKYBLUE (75 5035);
FORCEPROP 1 LAST VALUE 1.00K
J 0
(-525 5030);
DISPLAY 0.617021 (-525 5030);
PAINT SKYBLUE (-525 5030);
FORCEPROP 1 LASTPIN (-500 5100) $PN 1
J 2
(-487 5120);
DISPLAY 0.617021 (-487 5120);
PAINT ORANGE (-487 5120);
FORCEPROP 1 LAST TOLERANCE 1%
J 0
(-375 5030);
DISPLAY 0.617021 (-375 5030);
PAINT SKYBLUE (-375 5030);
FORCEPROP 1 LAST LOCATION R3P7
J 0
(-600 5180);
DISPLAY 0.617021 (-600 5180);
PAINT AQUA (-600 5180);
FORCEPROP 1 LASTPIN (-300 5100) $PN 2
J 2
(-260 5120);
DISPLAY 0.617021 (-260 5120);
PAINT ORANGE (-260 5120);
FORCEPROP 1 LAST PART_NUMBER G21796-026
J 0
(-225 5110);
DISPLAY 0.617021 (-225 5110);
PAINT BLUE (-225 5110);
FORCEPROP 1 LAST PACK_TYPE 0402
J 0
(-275 5035);
DISPLAY 0.617021 (-275 5035);
PAINT SKYBLUE (-275 5035);
FORCEPROP 0 LAST CDS_SEC 1
R 1
J 0
(-500 5350);
PAINT MONO (-500 5350);
DISPLAY INVISIBLE (-500 5350);
FORCEPROP 2 LAST CDS_LIB mstr_discrete
R 1
J 0
(-400 5100);
PAINT ORANGE (-400 5100);
DISPLAY INVISIBLE (-400 5100);
FORCEPROP 0 LAST ROOM DEBUG
R 1
J 2
(-525 5075);
DISPLAY 1.021277 (-525 5075);
PAINT ORANGE (-525 5075);
DISPLAY INVISIBLE (-525 5075);
FORCEPROP 2 LAST SEC 1
R 1
J 0
(-625 5050);
DISPLAY 0.680851 (-625 5050);
PAINT MONO (-625 5050);
DISPLAY INVISIBLE (-625 5050);
FORCEPROP 2 LAST SEC_TYPE 0402
R 1
J 0
(-625 5050);
DISPLAY 1.021277 (-625 5050);
PAINT ORANGE (-625 5050);
DISPLAY INVISIBLE (-625 5050);
FORCEPROP 1 LAST PATH I370
R 1
J 2
(-575 5050);
DISPLAY 0.978723 (-575 5050);
PAINT WHITE (-575 5050);
DISPLAY INVISIBLE (-575 5050);
FORCEPROP 2 LAST CDS_LOCATION R3P7
R 1
J 2
(-375 5280);
DISPLAY 0.617021 (-375 5280);
PAINT AQUA (-375 5280);
DISPLAY INVISIBLE (-375 5280);
FORCEADD RES..1
(-4700 3475);
FORCEPROP 1 LAST VALUE 4.75K
J 2
(-4700 3425);
DISPLAY 0.617021 (-4700 3425);
PAINT SKYBLUE (-4700 3425);
FORCEPROP 1 LAST WATTAGE 1/16W
J 2
(-4450 3425);
DISPLAY 0.617021 (-4450 3425);
PAINT SKYBLUE (-4450 3425);
FORCEPROP 1 LASTPIN (-4800 3475) $PN 1
J 0
(-4788 3487);
DISPLAY 0.617021 (-4788 3487);
PAINT ORANGE (-4788 3487);
FORCEPROP 1 LAST TOLERANCE 1%
J 0
(-4675 3425);
DISPLAY 0.617021 (-4675 3425);
PAINT SKYBLUE (-4675 3425);
FORCEPROP 1 LAST MATERIAL CHIP
J 0
(-4425 3425);
DISPLAY 0.617021 (-4425 3425);
PAINT SKYBLUE (-4425 3425);
FORCEPROP 1 LAST PART_NUMBER G21796-072
J 0
(-4175 3425);
DISPLAY 0.617021 (-4175 3425);
PAINT BLUE (-4175 3425);
FORCEPROP 1 LASTPIN (-4600 3475) $PN 2
J 0
(-4638 3487);
DISPLAY 0.617021 (-4638 3487);
PAINT ORANGE (-4638 3487);
FORCEPROP 1 LAST LOCATION R8E3
J 0
(-4750 3525);
DISPLAY 0.617021 (-4750 3525);
PAINT AQUA (-4750 3525);
FORCEPROP 1 LAST PACK_TYPE 0402
J 0
(-4300 3425);
DISPLAY 0.617021 (-4300 3425);
PAINT SKYBLUE (-4300 3425);
FORCEPROP 2 LAST SEC_TYPE 0402
J 0
(-4750 3675);
DISPLAY 1.021277 (-4750 3675);
PAINT ORANGE (-4750 3675);
DISPLAY INVISIBLE (-4750 3675);
FORCEPROP 2 LAST SEC 1
J 0
(-4750 3675);
DISPLAY 0.680851 (-4750 3675);
PAINT MONO (-4750 3675);
DISPLAY INVISIBLE (-4750 3675);
FORCEPROP 2 LAST ROOM SB_PU_PD
J 0
(-4750 3575);
DISPLAY 1.021277 (-4750 3575);
PAINT ORANGE (-4750 3575);
DISPLAY INVISIBLE (-4750 3575);
FORCEPROP 2 LAST CDS_LIB mstr_discrete
J 0
(-4700 3475);
PAINT MONO (-4700 3475);
DISPLAY INVISIBLE (-4700 3475);
FORCEPROP 1 LAST PATH I371
J 0
(-4750 3625);
DISPLAY 0.978723 (-4750 3625);
PAINT WHITE (-4750 3625);
DISPLAY INVISIBLE (-4750 3625);
FORCEPROP 2 LAST CDS_LOCATION R8E3
J 0
(-4750 3525);
DISPLAY 0.617021 (-4750 3525);
PAINT AQUA (-4750 3525);
DISPLAY INVISIBLE (-4750 3525);
FORCEADD DNS..2
(-2495 4070);
PAINT RED (-2495 4070);
FORCEPROP 2 LAST CDS_LIB mstr_misc
J 0
(-2495 4070);
PAINT ORANGE (-2495 4070);
DISPLAY INVISIBLE (-2495 4070);
FORCEPROP 1 LAST COMMENT_BODY TRUE
R 1
J 0
(-2420 3845);
DISPLAY 0.872340 (-2420 3845);
PAINT GREEN (-2420 3845);
DISPLAY INVISIBLE (-2420 3845);
FORCEADD DNS..2
(-370 4420);
PAINT RED (-370 4420);
FORCEPROP 2 LAST CDS_LIB mstr_misc
J 0
(-370 4420);
PAINT ORANGE (-370 4420);
DISPLAY INVISIBLE (-370 4420);
FORCEPROP 1 LAST COMMENT_BODY TRUE
R 1
J 0
(-295 4195);
DISPLAY 0.872340 (-295 4195);
PAINT GREEN (-295 4195);
DISPLAY INVISIBLE (-295 4195);
FORCEADD DNS..2
(-370 4670);
PAINT RED (-370 4670);
FORCEPROP 2 LAST CDS_LIB mstr_misc
J 0
(-370 4670);
PAINT ORANGE (-370 4670);
DISPLAY INVISIBLE (-370 4670);
FORCEPROP 1 LAST COMMENT_BODY TRUE
R 1
J 0
(-295 4445);
DISPLAY 0.872340 (-295 4445);
PAINT GREEN (-295 4445);
DISPLAY INVISIBLE (-295 4445);
FORCEADD DESIGN_NOTE..1
(-400 3300);
FORCEPROP 0 LAST L1 GPIO L FAMILY IS ON P1V05_PCH_STBY
J 0
(-600 3175);
DISPLAY 0.808511 (-600 3175);
PAINT ORANGE (-600 3175);
FORCEPROP 2 LAST CDS_LIB mstr_symbols
J 0
(-400 3300);
PAINT ORANGE (-400 3300);
DISPLAY INVISIBLE (-400 3300);
FORCEPROP 1 LAST COMMENT_BODY TRUE
J 0
(-375 3400);
DISPLAY 0.978723 (-375 3400);
PAINT ORANGE (-375 3400);
DISPLAY INVISIBLE (-375 3400);
FORCEADD DNS..2
(-395 5120);
PAINT RED (-395 5120);
FORCEPROP 2 LAST CDS_LIB mstr_misc
J 0
(-395 5120);
PAINT ORANGE (-395 5120);
DISPLAY INVISIBLE (-395 5120);
FORCEPROP 1 LAST COMMENT_BODY TRUE
R 1
J 0
(-320 4895);
DISPLAY 0.872340 (-320 4895);
PAINT GREEN (-320 4895);
DISPLAY INVISIBLE (-320 4895);
FORCEADD DNS..2
(-395 4895);
PAINT RED (-395 4895);
FORCEPROP 2 LAST CDS_LIB mstr_misc
J 0
(-395 4895);
PAINT ORANGE (-395 4895);
DISPLAY INVISIBLE (-395 4895);
FORCEPROP 1 LAST COMMENT_BODY TRUE
R 1
J 0
(-320 4670);
DISPLAY 0.872340 (-320 4670);
PAINT GREEN (-320 4670);
DISPLAY INVISIBLE (-320 4670);
FORCEADD INTEL_CORP_BPAGE..1
(2650 500);
FORCEPROP 1 LAST CDS_CON_LAST_MODIFIED Fri Jun 16 17:48:51 2017
J 0
(1225 825);
PAINT ORANGE (1225 825);
DISPLAY INVISIBLE (1225 825);
FORCEPROP 1 LAST CUSTOM_TXT_CDS <CURRENT_DESIGN_SHEET> OF <TOTAL_DESIGN_SHEETS>
J 0
(2150 525);
PAINT ORANGE (2150 525);
FORCEPROP 1 LAST CUSTOM_TXT_CDS <CON_LAST_MODIFIED>
J 0
(-1350 600);
PAINT ORANGE (-1350 600);
FORCEPROP 2 LAST CUSTOM_TXT_CDS <XR_PAGE_TITLE>
J 0
(-5240 5750);
DISPLAY 0.638298 (-5240 5750);
PAINT PINK (-5240 5750);
DISPLAY INVISIBLE (-5240 5750);
FORCEPROP 1 LAST SCH_TITLE LBG PULLUPS/PULLDOWNS
J 0
(-5300 550);
DISPLAY 1.212766 (-5300 550);
PAINT ORANGE (-5300 550);
FORCEPROP 2 LAST PAGE_BORDER TRUE
J 0
(-5240 5750);
DISPLAY 0.851064 (-5240 5750);
PAINT PINK (-5240 5750);
DISPLAY INVISIBLE (-5240 5750);
FORCEPROP 2 LAST BOM_COST SB
J 0
(-5225 5800);
PAINT MONO (-5225 5800);
DISPLAY INVISIBLE (-5225 5800);
FORCEPROP 2 LAST CDS_LIB mstr_symbols
J 0
(2650 500);
PAINT MONO (2650 500);
DISPLAY INVISIBLE (2650 500);
FORCEPROP 1 LAST COMMENT_BODY TRUE
J 0
(2662 512);
DISPLAY 0.468085 (2662 512);
PAINT GREEN (2662 512);
DISPLAY INVISIBLE (2662 512);
FORCEPROP 2 LAST CDS_XR_PAGE_TITLE CR-133 : @BASEBOARD_FAB2_LIB.BASEBOARD_FAB2(SCH_1):PAGE133
J 0
(-5240 5750);
DISPLAY 0.638298 (-5240 5750);
PAINT PINK (-5240 5750);
DISPLAY INVISIBLE (-5240 5750);
FORCEADD DNS..2
(-370 4195);
PAINT RED (-370 4195);
FORCEPROP 2 LAST CDS_LIB mstr_misc
J 0
(-370 4195);
PAINT ORANGE (-370 4195);
DISPLAY INVISIBLE (-370 4195);
FORCEPROP 1 LAST COMMENT_BODY TRUE
R 1
J 0
(-295 3970);
DISPLAY 0.872340 (-295 3970);
PAINT GREEN (-295 3970);
DISPLAY INVISIBLE (-295 3970);
WIRE 16 -1 (-2825 3650)(-2825 3850);
WIRE 16 -1 (-2825 3850)(-2825 4075);
WIRE 16 -1 (-2600 3850)(-2825 3850);
WIRE 16 -1 (-2600 4075)(-2825 4075);
WIRE 16 -1 (-4950 2725)(-4950 2875);
WIRE 16 -1 (-4950 2400)(-4950 2725);
WIRE 16 -1 (-4950 2725)(-4750 2725);
WIRE 16 -1 (-4950 2400)(-4775 2400);
WIRE 16 -1 (-5075 1825)(-5075 1925);
WIRE 16 -1 (-5075 1825)(-5075 1650);
WIRE 16 -1 (-5075 1825)(-4900 1825);
WIRE 16 -1 (-5075 1500)(-5075 1650);
WIRE 16 -1 (-5075 1650)(-4900 1650);
WIRE 16 -1 (-5075 1300)(-5075 1500);
WIRE 16 -1 (-4900 1500)(-5075 1500);
WIRE 16 -1 (-5075 1125)(-5075 1300);
WIRE 16 -1 (-5075 1300)(-4900 1300);
WIRE 16 -1 (-5075 950)(-5075 1125);
WIRE 16 -1 (-4900 1125)(-5075 1125);
WIRE 16 -1 (-4900 950)(-5075 950);
WIRE 16 -1 (-2825 5300)(-2825 5125);
WIRE 16 -1 (-2825 4900)(-2825 5125);
WIRE 16 -1 (-2700 5125)(-2825 5125);
WIRE 16 -1 (-2825 4675)(-2825 4900);
WIRE 16 -1 (-2700 4900)(-2825 4900);
WIRE 16 -1 (-2825 4675)(-2825 4425);
WIRE 16 -1 (-2675 4675)(-2825 4675);
WIRE 16 -1 (-2675 4425)(-2825 4425);
WIRE 16 -1 (-2750 1375)(-2750 1275);
WIRE 16 -1 (-2750 1025)(-2750 1275);
WIRE 16 -1 (-2750 1275)(-2575 1275);
WIRE 16 -1 (-2750 1025)(-2575 1025);
WIRE 16 -1 (-650 1800)(-650 1700);
WIRE 16 -1 (-425 1700)(-650 1700);
WIRE 16 -1 (-650 1525)(-650 1700);
WIRE 16 -1 (-175 1700)(-425 1700);
WIRE 16 -1 (-425 1525)(-425 1700);
WIRE 16 -1 (-175 1525)(-175 1700);
WIRE 16 -1 (-2800 2000)(-2800 1800);
WIRE 16 -1 (-2800 1800)(-2575 1800);
WIRE 16 -1 (-4950 5100)(-4950 5175);
WIRE 16 -1 (-4950 5100)(-4950 4900);
WIRE 16 -1 (-4950 5100)(-4800 5100);
WIRE 16 -1 (-4950 4900)(-4950 4700);
WIRE 16 -1 (-4950 4900)(-4800 4900);
WIRE 16 -1 (-4950 4500)(-4950 4700);
WIRE 16 -1 (-4950 4700)(-4800 4700);
WIRE 16 -1 (-4950 4325)(-4950 4500);
WIRE 16 -1 (-4950 4500)(-4800 4500);
WIRE 16 -1 (-4950 4125)(-4950 4325);
WIRE 16 -1 (-4950 4325)(-4800 4325);
WIRE 16 -1 (-4950 4125)(-4950 3925);
WIRE 16 -1 (-4950 4125)(-4800 4125);
WIRE 16 -1 (-4950 3700)(-4950 3925);
WIRE 16 -1 (-4950 3925)(-4800 3925);
WIRE 16 -1 (-4950 3700)(-4950 3475);
WIRE 16 -1 (-4950 3700)(-4800 3700);
WIRE 16 -1 (-4950 3475)(-4800 3475);
WIRE 16 -1 (-2775 3150)(-2775 3375);
WIRE 16 -1 (-2775 3150)(-2600 3150);
WIRE 16 -1 (-625 5275)(-625 5100);
WIRE 16 -1 (-625 4875)(-625 5100);
WIRE 16 -1 (-500 5100)(-625 5100);
WIRE 16 -1 (-625 4650)(-625 4875);
WIRE 16 -1 (-500 4875)(-625 4875);
WIRE 16 -1 (-625 4650)(-625 4400);
WIRE 16 -1 (-475 4650)(-625 4650);
WIRE 16 -1 (-625 4175)(-625 4400);
WIRE 16 -1 (-475 4400)(-625 4400);
WIRE 16 -1 (-625 4175)(-625 3925);
WIRE 16 -1 (-475 4175)(-625 4175);
WIRE 16 -1 (-625 3925)(-625 3725);
WIRE 16 -1 (-475 3925)(-625 3925);
WIRE 16 -1 (-625 3725)(-625 3525);
WIRE 16 -1 (-625 3725)(-475 3725);
WIRE 16 -1 (-625 3525)(-475 3525);
WIRE 16 -1 (-2800 2825)(-2800 2700);
WIRE 16 -1 (-2800 2450)(-2800 2700);
WIRE 16 -1 (-2800 2700)(-2575 2700);
WIRE 16 -1 (-2575 2450)(-2800 2450);
WIRE 16 -1 (-625 2900)(-625 2725);
WIRE 16 -1 (-625 2475)(-625 2725);
WIRE 16 -1 (-625 2725)(-475 2725);
WIRE 16 -1 (-625 2475)(-475 2475);
WIRE 16 -1 (-2475 4425)(-1725 4425);
FORCEPROP 0 LAST SIG_NAME FM_XRC_READY_N
J 0
(-2110 4435);
DISPLAY 0.617021 (-2110 4435);
PAINT ORANGE (-2110 4435);
WIRE 16 -1 (75 1550)(75 1450);
WIRE 16 -1 (75 1450)(800 1450);
WIRE 16 -1 (75 1550)(2450 1550);
WIRE 16 -1 (75 1650)(75 1550);
WIRE 16 -1 (75 1650)(2450 1650);
WIRE 16 -1 (2450 1550)(2450 1650);
WIRE 16 -1 (75 1750)(75 1650);
WIRE 16 -1 (2450 1550)(2450 1450);
WIRE 16 -1 (800 2050)(800 1450);
WIRE 16 -1 (800 1450)(1275 1450);
WIRE 16 -1 (1275 2050)(1275 1450);
WIRE 16 -1 (1275 2050)(800 2050);
WIRE 16 -1 (1775 1450)(1275 1450);
WIRE 16 -1 (2450 1450)(1775 1450);
WIRE 16 -1 (800 2050)(75 2050);
WIRE 16 -1 (75 1750)(2450 1750);
WIRE 16 -1 (2450 1650)(2450 1750);
WIRE 16 -1 (75 1850)(75 1750);
WIRE 16 -1 (75 1850)(2450 1850);
WIRE 16 -1 (2450 1750)(2450 1850);
WIRE 16 -1 (75 1950)(75 1850);
WIRE 16 -1 (75 2050)(75 1950);
WIRE 16 -1 (1775 2050)(1775 1450);
WIRE 16 -1 (1775 2050)(1275 2050);
WIRE 16 -1 (2450 2050)(1775 2050);
WIRE 16 -1 (75 1950)(2450 1950);
WIRE 16 -1 (2450 1850)(2450 1950);
WIRE 16 -1 (2450 1950)(2450 2050);
WIRE 16 -1 (-4600 3925)(-3900 3925);
FORCEPROP 2 LAST SIG_NAME FM_OCP_MEZZA_PRES
J 0
(-4435 3935);
DISPLAY 0.617021 (-4435 3935);
PAINT ORANGE (-4435 3935);
WIRE 16 -1 (-4600 3475)(-3900 3475);
FORCEPROP 2 LAST SIG_NAME FM_TPM_PRES_N
J 0
(-4425 3485);
DISPLAY 0.617021 (-4425 3485);
PAINT ORANGE (-4425 3485);
WIRE 16 273 (-950 4275)(-950 5475);
WIRE 16 273 (-3050 5500)(-3050 4275);
WIRE 16 273 (-3050 4275)(-950 4275);
WIRE 16 273 (-950 3550)(-950 4275);
WIRE 16 273 (-950 3125)(-950 3550);
WIRE 16 273 (-950 3125)(1150 3125);
WIRE 16 273 (-3050 3550)(-950 3550);
WIRE 16 273 (-3050 4275)(-3050 3550);
WIRE 16 273 (-5275 3100)(-3050 3100);
WIRE 16 273 (-3050 3550)(-3050 3100);
WIRE 16 273 (-950 3000)(-950 3125);
WIRE 16 273 (-950 900)(-950 2275);
WIRE 16 273 (-950 2275)(-950 3000);
WIRE 16 273 (-3050 3000)(-3050 3100);
WIRE 16 273 (-3050 3000)(-950 3000);
WIRE 16 273 (-3050 2275)(-3050 3000);
WIRE 16 273 (-3050 2275)(-950 2275);
WIRE 16 273 (-5200 2125)(-3050 2125);
WIRE 16 273 (-3050 2275)(-3050 2125);
WIRE 16 273 (-3050 1525)(-3050 2125);
WIRE 16 273 (-3050 1525)(-975 1525);
WIRE 16 273 (-3050 725)(-3050 1525);
WIRE 16 -1 (-4600 3700)(-3900 3700);
FORCEPROP 2 LAST SIG_NAME FM_BMC_READY_N
J 0
(-4425 3710);
DISPLAY 0.617021 (-4425 3710);
PAINT ORANGE (-4425 3710);
WIRE 3 682 (-4850 3600)(-4850 3400);
WIRE 3 682 (-4550 3600)(-4850 3600);
WIRE 3 682 (-4850 3400)(-4550 3400);
WIRE 3 682 (-4550 3400)(-4550 3600);
WIRE 3 682 (-150 4050)(-700 4050);
WIRE 3 682 (-150 5000)(-150 4050);
WIRE 3 682 (-700 4050)(-700 5000);
WIRE 3 682 (-700 5000)(-150 5000);
WIRE 16 -1 (-300 5100)(575 5100);
FORCEPROP 2 LAST SIG_NAME FM_PRSNT_2_1_N
J 0
(15 5110);
DISPLAY 0.617021 (15 5110);
PAINT ORANGE (15 5110);
WIRE 3 2175 (-650 3825)(1200 3825);
WIRE 3 2175 (1200 3825)(1200 3450);
WIRE 3 2175 (-650 3825)(-650 3450);
WIRE 3 2175 (-650 3450)(1200 3450);
WIRE 16 -1 (-275 3525)(725 3525);
FORCEPROP 2 LAST SIG_NAME FM_OCP_MEZZC_PRES_1V05_PCH_N
J 0
(-60 3535);
DISPLAY 0.617021 (-60 3535);
PAINT ORANGE (-60 3535);
WIRE 16 -1 (-300 4875)(575 4875);
FORCEPROP 2 LAST SIG_NAME FM_PRSNT_2_2_N
J 0
(15 4885);
DISPLAY 0.617021 (15 4885);
PAINT ORANGE (15 4885);
WIRE 16 -1 (-275 4650)(575 4650);
FORCEPROP 2 LAST SIG_NAME FM_PRSNT_2_3_N
J 0
(15 4660);
DISPLAY 0.617021 (15 4660);
PAINT ORANGE (15 4660);
WIRE 16 -1 (-275 4400)(575 4400);
FORCEPROP 2 LAST SIG_NAME FM_PRSNT_2_4_N
J 0
(15 4410);
DISPLAY 0.617021 (15 4410);
PAINT ORANGE (15 4410);
WIRE 16 -1 (-275 4175)(575 4175);
FORCEPROP 2 LAST SIG_NAME FM_PRSNT_2_5_N
J 0
(15 4185);
DISPLAY 0.617021 (15 4185);
PAINT ORANGE (15 4185);
WIRE 16 -1 (-275 3925)(575 3925);
FORCEPROP 2 LAST SIG_NAME FM_PRSNT_2_6_N
J 0
(0 3935);
DISPLAY 0.617021 (0 3935);
PAINT ORANGE (0 3935);
WIRE 16 -1 (-275 3725)(725 3725);
FORCEPROP 2 LAST SIG_NAME FM_OCP_MEZZB_PRES_1V05_PCH_N
J 0
(-60 3735);
DISPLAY 0.617021 (-60 3735);
PAINT ORANGE (-60 3735);
WIRE 16 -1 (-275 2725)(575 2725);
FORCEPROP 2 LAST SIG_NAME FM_CPU0_RC_ERROR_N
J 0
(15 2735);
DISPLAY 0.617021 (15 2735);
PAINT ORANGE (15 2735);
WIRE 16 -1 (-2375 1025)(-1700 1025);
FORCEPROP 0 LAST SIG_NAME IRQ_BOARD_BMC_ALERT_N
J 0
(-2250 1035);
DISPLAY 0.617021 (-2250 1035);
PAINT ORANGE (-2250 1035);
WIRE 16 -1 (-2375 1275)(-1700 1275);
FORCEPROP 2 LAST SIG_NAME PU_10GBE_LOM_PCI_DISABLE_N
J 0
(-2250 1285);
DISPLAY 0.617021 (-2250 1285);
PAINT ORANGE (-2250 1285);
WIRE 16 -1 (-2375 1800)(-1625 1800);
FORCEPROP 0 LAST SIG_NAME FP_PWR_ID_LED_N
J 0
(-2250 1810);
DISPLAY 0.617021 (-2250 1810);
PAINT ORANGE (-2250 1810);
WIRE 16 -1 (-2375 2450)(-1625 2450);
FORCEPROP 0 LAST SIG_NAME FM_CPU0_RC_EN
J 0
(-2175 2460);
DISPLAY 0.617021 (-2175 2460);
PAINT ORANGE (-2175 2460);
WIRE 16 -1 (-2375 2700)(-1625 2700);
FORCEPROP 0 LAST SIG_NAME FM_BIOS_SMI_ACTIVE_N
J 0
(-2175 2710);
DISPLAY 0.617021 (-2175 2710);
PAINT ORANGE (-2175 2710);
WIRE 16 -1 (-2400 3150)(-1650 3150);
FORCEPROP 0 LAST SIG_NAME IRQ_PCH_NIC_ALERT_N
J 0
(-2175 3160);
DISPLAY 0.617021 (-2175 3160);
PAINT ORANGE (-2175 3160);
WIRE 16 -1 (-2400 3850)(-1650 3850);
FORCEPROP 2 LAST SIG_NAME PWRGD_PCH_PWROK
J 2
(-1735 3860);
DISPLAY 0.617021 (-1735 3860);
PAINT ORANGE (-1735 3860);
WIRE 16 -1 (-2400 4075)(-1650 4075);
FORCEPROP 2 LAST SIG_NAME PWRGD_SYS_PWROK
J 2
(-1735 4085);
DISPLAY 0.617021 (-1735 4085);
PAINT ORANGE (-1735 4085);
WIRE 16 -1 (-2475 4675)(-1725 4675);
FORCEPROP 0 LAST SIG_NAME FM_XRC_PRESENT_N
J 0
(-2110 4685);
DISPLAY 0.617021 (-2110 4685);
PAINT ORANGE (-2110 4685);
WIRE 16 -1 (-2500 4900)(-1750 4900);
FORCEPROP 0 LAST SIG_NAME IRQ_HSC_FAULT_N
J 0
(-2135 4910);
DISPLAY 0.617021 (-2135 4910);
PAINT ORANGE (-2135 4910);
WIRE 16 -1 (-2500 5125)(-1750 5125);
FORCEPROP 0 LAST SIG_NAME FM_PCH_PLD_DATA
J 0
(-2135 5135);
DISPLAY 0.617021 (-2135 5135);
PAINT ORANGE (-2135 5135);
WIRE 16 -1 (-4700 1125)(-3975 1125);
FORCEPROP 2 LAST SIG_NAME FM_SLT_CFG0
J 0
(-4475 1135);
DISPLAY 0.617021 (-4475 1135);
PAINT ORANGE (-4475 1135);
WIRE 16 -1 (-4700 950)(-3975 950);
FORCEPROP 0 LAST SIG_NAME IRQ_BMC_PCH_SMI_LPC_N
J 0
(-4475 960);
DISPLAY 0.617021 (-4475 960);
PAINT ORANGE (-4475 960);
WIRE 16 -1 (-4700 1650)(-3975 1650);
FORCEPROP 0 LAST SIG_NAME FM_THROTTLE_N
J 0
(-4475 1660);
DISPLAY 0.617021 (-4475 1660);
PAINT ORANGE (-4475 1660);
WIRE 16 -1 (-4700 1500)(-3975 1500);
FORCEPROP 0 LAST SIG_NAME FM_CPU1_RC_EN
J 0
(-4475 1510);
DISPLAY 0.617021 (-4475 1510);
PAINT ORANGE (-4475 1510);
WIRE 16 -1 (-4700 1825)(-3975 1825);
FORCEPROP 2 LAST SIG_NAME IRQ_BMC_PCH_SCI_LPC_N
J 0
(-4475 1835);
DISPLAY 0.617021 (-4475 1835);
PAINT ORANGE (-4475 1835);
WIRE 16 -1 (-4575 2400)(-3750 2400);
FORCEPROP 0 LAST SIG_NAME FM_BIOS_POST_CMPLT_N
J 0
(-4235 2410);
DISPLAY 0.617021 (-4235 2410);
PAINT ORANGE (-4235 2410);
WIRE 16 -1 (-4550 2725)(-3750 2725);
FORCEPROP 2 LAST SIG_NAME PU_IRQ_VRALERT_N
J 0
(-4235 2735);
DISPLAY 0.617021 (-4235 2735);
PAINT ORANGE (-4235 2735);
WIRE 16 -1 (-4600 4125)(-3900 4125);
FORCEPROP 0 LAST SIG_NAME PU_IRQ_PCH_SCI_WHEA_N
J 0
(-4435 4135);
DISPLAY 0.617021 (-4435 4135);
PAINT ORANGE (-4435 4135);
WIRE 16 -1 (-4600 4325)(-3900 4325);
FORCEPROP 0 LAST SIG_NAME PU_LPC_PME_N
J 0
(-4435 4335);
DISPLAY 0.617021 (-4435 4335);
PAINT ORANGE (-4435 4335);
WIRE 16 -1 (-4600 4700)(-3900 4700);
FORCEPROP 0 LAST SIG_NAME IRQ_PIRQA_SPI_TPM_N
J 0
(-4435 4710);
DISPLAY 0.617021 (-4435 4710);
PAINT ORANGE (-4435 4710);
WIRE 16 -1 (-4600 5100)(-3900 5100);
WIRE 16 -1 (-4600 4900)(-3900 4900);
FORCEPROP 0 LAST SIG_NAME IRQ_LPC_SERIRQ_N
J 0
(-4435 4910);
DISPLAY 0.617021 (-4435 4910);
PAINT ORANGE (-4435 4910);
WIRE 16 -1 (-4600 4500)(-3900 4500);
FORCEPROP 0 LAST SIG_NAME PU_LPC_CLKRUN_N
J 0
(-4435 4510);
DISPLAY 0.617021 (-4435 4510);
PAINT ORANGE (-4435 4510);
WIRE 16 273 (1225 5425)(1225 2275);
WIRE 16 -1 (-425 1075)(-425 1325);
WIRE 16 -1 (1325 1075)(-425 1075);
FORCEPROP 0 LAST SIG_NAME FM_WBG_PRSNT_N
J 0
(440 1085);
DISPLAY 0.617021 (440 1085);
PAINT ORANGE (440 1085);
WIRE 16 -1 (-650 1325)(-650 1000);
WIRE 16 -1 (-650 1000)(1325 1000);
FORCEPROP 0 LAST SIG_NAME FM_SINT_PRSNT_N
J 0
(440 1010);
DISPLAY 0.617021 (440 1010);
PAINT ORANGE (440 1010);
WIRE 16 -1 (-175 1325)(-175 1150);
WIRE 16 -1 (-175 1150)(1325 1150);
FORCEPROP 0 LAST SIG_NAME FM_PCH_PRSNT_N
J 0
(440 1160);
DISPLAY 0.617021 (440 1160);
PAINT ORANGE (440 1160);
WIRE 16 -1 (-275 2475)(575 2475);
FORCEPROP 2 LAST SIG_NAME FM_CPU1_RC_ERROR_N
J 0
(15 2485);
DISPLAY 0.617021 (15 2485);
PAINT ORANGE (15 2485);
WIRE 16 -1 (-4700 1300)(-3975 1300);
FORCEPROP 2 LAST SIG_NAME FM_SLT_CFG1
J 0
(-4475 1310);
DISPLAY 0.617021 (-4475 1310);
PAINT ORANGE (-4475 1310);
WIRE 16 273 (-800 2250)(2550 2250);
DOT 1 (-625 4875);
DOT 1 (-625 4650);
DOT 1 (-625 4400);
DOT 1 (-625 4175);
DOT 1 (-625 2725);
DOT 1 (75 1850);
DOT 1 (-2750 1275);
DOT 1 (-4950 4500);
DOT 1 (2450 1850);
DOT 1 (2450 1950);
DOT 1 (2450 1750);
DOT 1 (2450 1650);
DOT 1 (2450 1550);
DOT 1 (800 2050);
DOT 1 (1275 2050);
DOT 1 (1775 2050);
DOT 1 (1775 1450);
DOT 1 (1275 1450);
DOT 1 (800 1450);
DOT 1 (75 1950);
DOT 1 (75 1750);
DOT 1 (75 1650);
DOT 1 (75 1550);
DOT 1 (-625 5100);
DOT 1 (-950 4275);
DOT 1 (-2825 5125);
DOT 1 (-2825 4675);
DOT 1 (-2825 4900);
DOT 1 (-3050 4275);
DOT 1 (-625 3925);
DOT 1 (-625 3725);
DOT 1 (-950 3125);
DOT 1 (-950 3550);
DOT 1 (-950 3000);
DOT 1 (-950 2275);
DOT 1 (-425 1700);
DOT 1 (-650 1700);
DOT 1 (-2825 3850);
DOT 1 (-3050 3100);
DOT 1 (-2800 2700);
DOT 1 (-3050 3000);
DOT 1 (-3050 2275);
DOT 1 (-3050 2125);
DOT 1 (-3050 1525);
DOT 1 (-4950 5100);
DOT 1 (-4950 4900);
DOT 1 (-4950 4700);
DOT 1 (-4950 4325);
DOT 1 (-4950 4125);
DOT 1 (-4950 3925);
DOT 1 (-4950 3700);
DOT 1 (-4950 2725);
DOT 1 (-5075 1825);
DOT 1 (-5075 1650);
DOT 1 (-5075 1500);
DOT 1 (-5075 1300);
DOT 1 (-5075 1125);
DOT 1 (-3050 3550);
FORCENOTE
PIN C18
(925 1975) 0;
DISPLAY LEFT (925 1975);
DISPLAY 1.021277 (925 1975);
PAINT PURPLE (925 1975);
FORCENOTE
TP FAB1 NOPOP RES 0307
(-125 4500) 0;
DISPLAY LEFT (-125 4500);
DISPLAY 0.808511 (-125 4500);
PAINT RED (-125 4500);
FORCENOTE
TP FAB1 RENAME 1218
(-25 3375) 0;
DISPLAY LEFT (-25 3375);
DISPLAY 1.021277 (-25 3375);
PAINT RED (-25 3375);
FORCENOTE
PCH DETECTION
(100 2075) 0;
DISPLAY LEFT (100 2075);
DISPLAY 1.276596 (100 2075);
PAINT PURPLE (100 2075);
FORCENOTE
CGC_DUT_DETECT#
(125 1975) 0;
DISPLAY LEFT (125 1975);
DISPLAY 1.021277 (125 1975);
PAINT PURPLE (125 1975);
FORCENOTE
GPP_I
(-1275 1425) 0;
DISPLAY LEFT (-1275 1425);
DISPLAY 1.021277 (-1275 1425);
PAINT PURPLE (-1275 1425);
FORCENOTE
GPP_G
(-1300 2850) 0;
DISPLAY LEFT (-1300 2850);
DISPLAY 1.021277 (-1300 2850);
PAINT PURPLE (-1300 2850);
FORCENOTE
GPP_L
(825 5325) 0;
DISPLAY LEFT (825 5325);
DISPLAY 1.021277 (825 5325);
PAINT PURPLE (825 5325);
FORCENOTE
GPP_D
(-1250 4300) 0;
DISPLAY LEFT (-1250 4300);
DISPLAY 1.021277 (-1250 4300);
PAINT PURPLE (-1250 4300);
FORCENOTE
GPP_F
(-1300 3425) 0;
DISPLAY LEFT (-1300 3425);
DISPLAY 1.021277 (-1300 3425);
PAINT PURPLE (-1300 3425);
FORCENOTE
COMMENT
(1900 1975) 0;
DISPLAY LEFT (1900 1975);
DISPLAY 1.021277 (1900 1975);
PAINT PURPLE (1900 1975);
FORCENOTE
GPP_A
(-3325 3175) 0;
DISPLAY LEFT (-3325 3175);
DISPLAY 1.021277 (-3325 3175);
PAINT PURPLE (-3325 3175);
FORCENOTE
GPP_B
(-3325 3000) 0;
DISPLAY LEFT (-3325 3000);
DISPLAY 1.021277 (-3325 3000);
PAINT PURPLE (-3325 3000);
FORCENOTE
1
(1500 1575) 0;
DISPLAY LEFT (1500 1575);
DISPLAY 1.021277 (1500 1575);
PAINT PURPLE (1500 1575);
FORCENOTE
X
(1500 1475) 0;
DISPLAY LEFT (1500 1475);
DISPLAY 1.021277 (1500 1475);
PAINT PURPLE (1500 1475);
FORCENOTE
1
(1500 1775) 0;
DISPLAY LEFT (1500 1775);
DISPLAY 1.021277 (1500 1775);
PAINT PURPLE (1500 1775);
FORCENOTE
0
(1025 1775) 0;
DISPLAY LEFT (1025 1775);
DISPLAY 1.021277 (1025 1775);
PAINT PURPLE (1025 1775);
FORCENOTE
1
(1025 1675) 0;
DISPLAY LEFT (1025 1675);
DISPLAY 1.021277 (1025 1675);
PAINT PURPLE (1025 1675);
FORCENOTE
1
(1025 1575) 0;
DISPLAY LEFT (1025 1575);
DISPLAY 1.021277 (1025 1575);
PAINT PURPLE (1025 1575);
FORCENOTE
X
(1025 1475) 0;
DISPLAY LEFT (1025 1475);
DISPLAY 1.021277 (1025 1475);
PAINT PURPLE (1025 1475);
FORCENOTE
0
(400 1775) 0;
DISPLAY LEFT (400 1775);
DISPLAY 1.021277 (400 1775);
PAINT PURPLE (400 1775);
FORCENOTE
0
(400 1575) 0;
DISPLAY LEFT (400 1575);
DISPLAY 1.021277 (400 1575);
PAINT PURPLE (400 1575);
FORCENOTE
0
(400 1675) 0;
DISPLAY LEFT (400 1675);
DISPLAY 1.021277 (400 1675);
PAINT PURPLE (400 1675);
FORCENOTE
1
(400 1475) 0;
DISPLAY LEFT (400 1475);
DISPLAY 1.021277 (400 1475);
PAINT PURPLE (400 1475);
FORCENOTE
GPP_E
(-1225 4175) 0;
DISPLAY LEFT (-1225 4175);
DISPLAY 1.021277 (-1225 4175);
PAINT PURPLE (-1225 4175);
FORCENOTE
GPP_H
(-1250 2150) 0;
DISPLAY LEFT (-1250 2150);
DISPLAY 1.021277 (-1250 2150);
PAINT PURPLE (-1250 2150);
FORCENOTE
ROOM=SB_PU_PD
(-3650 550) 0;
DISPLAY LEFT (-3650 550);
DISPLAY 1.021277 (-3650 550);
PAINT PURPLE (-3650 550);
FORCENOTE
GPP_C
(-3375 2000) 0;
DISPLAY LEFT (-3375 2000);
DISPLAY 1.021277 (-3375 2000);
PAINT PURPLE (-3375 2000);
FORCENOTE
INSTALLED WRONG DIRECTION
(1825 1475) 0;
DISPLAY LEFT (1825 1475);
DISPLAY 0.638298 (1825 1475);
PAINT PURPLE (1825 1475);
FORCENOTE
LBG
(2000 1575) 0;
DISPLAY LEFT (2000 1575);
DISPLAY 0.808511 (2000 1575);
PAINT PURPLE (2000 1575);
FORCENOTE
SINT_PRSNT
(825 1875) 0;
DISPLAY LEFT (825 1875);
DISPLAY 1.021277 (825 1875);
PAINT PURPLE (825 1875);
FORCENOTE
PIN D8
(1400 1975) 0;
DISPLAY LEFT (1400 1975);
DISPLAY 1.021277 (1400 1975);
PAINT PURPLE (1400 1975);
FORCENOTE
WBG_PRSNT
(1350 1875) 0;
DISPLAY LEFT (1350 1875);
DISPLAY 1.021277 (1350 1875);
PAINT PURPLE (1350 1875);
FORCENOTE
WBG
(2000 1675) 0;
DISPLAY LEFT (2000 1675);
DISPLAY 0.808511 (2000 1675);
PAINT PURPLE (2000 1675);
FORCENOTE
RSVD
(2000 1775) 0;
DISPLAY LEFT (2000 1775);
DISPLAY 0.808511 (2000 1775);
PAINT PURPLE (2000 1775);
FORCENOTE
TP FAB1 NOPOP RES 0309
(-150 5175) 0;
DISPLAY LEFT (-150 5175);
DISPLAY 0.808511 (-150 5175);
PAINT RED (-150 5175);
FORCENOTE
0
(1500 1675) 0;
DISPLAY LEFT (1500 1675);
DISPLAY 1.021277 (1500 1675);
PAINT PURPLE (1500 1675);
FORCENOTE
TP FAB3 CHANGE RES FROM 10K TO 4.75K 1004
(-4850 3350) 0;
DISPLAY LEFT (-4850 3350);
DISPLAY 0.638298 (-4850 3350);
PAINT RED (-4850 3350);
QUIT
